FILE_TYPE = MACRO_DRAWING;
SET COLOR_WIRE YELLOW;
SET COLOR_PROP ORANGE;
SET COLOR_DOT WHITE;
SET COLOR_ARC YELLOW;
SET COLOR_BODY GREEN;
SET COLOR_NOTE PURPLE;
SET PROP_DISPLAY VALUE;
SET PAGE_NUMBER P314;
FORCEADD OFFPAGE..1
(-3425 -1675);
FORCEPROP 2 LAST $XR0 213 
J 0
(-3677 -1675);
DISPLAY 0.638298 (-3677 -1675);
PAINT MONO (-3677 -1675);
FORCEPROP 2 LAST PATH I1
J 0
(-3675 -1625);
DISPLAY 1.021277 (-3675 -1625);
DISPLAY INVISIBLE (-3675 -1625);
FORCEPROP 1 LAST OFFPAGE TRUE
J 0
(-3100 -1800);
DISPLAY 0.872340 (-3100 -1800);
DISPLAY INVISIBLE (-3100 -1800);
FORCEPROP 1 LAST COMMENT_BODY TRUE
J 0
(-3300 -1775);
DISPLAY 1.170213 (-3300 -1775);
PAINT GREEN (-3300 -1775);
DISPLAY INVISIBLE (-3300 -1775);
FORCEPROP 2 LAST CDS_LIB standard
J 0
(-3425 -1675);
DISPLAY INVISIBLE (-3425 -1675);
FORCEADD OFFPAGE..1
(-3425 -125);
FORCEPROP 2 LAST $XR0 147 
J 0
(-3677 -125);
DISPLAY 0.638298 (-3677 -125);
PAINT MONO (-3677 -125);
FORCEPROP 2 LAST PATH I10
J 0
(-3675 -75);
DISPLAY 1.021277 (-3675 -75);
DISPLAY INVISIBLE (-3675 -75);
FORCEPROP 2 LAST CDS_LIB standard
J 0
(-3425 -125);
DISPLAY INVISIBLE (-3425 -125);
FORCEPROP 1 LAST OFFPAGE TRUE
J 0
(-3100 -250);
DISPLAY 0.872340 (-3100 -250);
DISPLAY INVISIBLE (-3100 -250);
FORCEPROP 1 LAST COMMENT_BODY TRUE
J 0
(-3300 -225);
DISPLAY 1.170213 (-3300 -225);
PAINT GREEN (-3300 -225);
DISPLAY INVISIBLE (-3300 -225);
FORCEADD OFFPAGE..1
(1500 -650);
FORCEPROP 2 LAST $XR1 305 
J 0
(1098 -650);
DISPLAY 0.638298 (1098 -650);
PAINT MONO (1098 -650);
FORCEPROP 2 LAST $XR0 301 
J 0
(1218 -650);
DISPLAY 0.638298 (1218 -650);
PAINT MONO (1218 -650);
FORCEPROP 2 LAST PATH I100
J 0
(1225 -600);
DISPLAY 1.021277 (1225 -600);
DISPLAY INVISIBLE (1225 -600);
FORCEPROP 2 LAST CDS_LIB standard
J 0
(1500 -650);
DISPLAY INVISIBLE (1500 -650);
FORCEPROP 1 LAST COMMENT_BODY TRUE
J 0
(1625 -750);
DISPLAY 1.170213 (1625 -750);
PAINT GREEN (1625 -750);
DISPLAY INVISIBLE (1625 -750);
FORCEPROP 1 LAST OFFPAGE TRUE
J 0
(1825 -775);
DISPLAY 0.872340 (1825 -775);
DISPLAY INVISIBLE (1825 -775);
FORCEADD OFFPAGE..1
(1500 -525);
FORCEPROP 2 LAST $XR0 148 
J 0
(1218 -525);
DISPLAY 0.638298 (1218 -525);
PAINT MONO (1218 -525);
FORCEPROP 2 LAST PATH I101
J 0
(1225 -475);
DISPLAY 1.021277 (1225 -475);
DISPLAY INVISIBLE (1225 -475);
FORCEPROP 2 LAST CDS_LIB standard
J 0
(1500 -525);
DISPLAY INVISIBLE (1500 -525);
FORCEPROP 1 LAST COMMENT_BODY TRUE
J 0
(1625 -625);
DISPLAY 1.170213 (1625 -625);
PAINT GREEN (1625 -625);
DISPLAY INVISIBLE (1625 -625);
FORCEPROP 1 LAST OFFPAGE TRUE
J 0
(1825 -650);
DISPLAY 0.872340 (1825 -650);
DISPLAY INVISIBLE (1825 -650);
FORCEADD OFFPAGE..1
(1500 -400);
FORCEPROP 2 LAST $XR0 148 
J 0
(1218 -400);
DISPLAY 0.638298 (1218 -400);
PAINT MONO (1218 -400);
FORCEPROP 2 LAST PATH I102
J 0
(1225 -350);
DISPLAY 1.021277 (1225 -350);
DISPLAY INVISIBLE (1225 -350);
FORCEPROP 2 LAST CDS_LIB standard
J 0
(1500 -400);
DISPLAY INVISIBLE (1500 -400);
FORCEPROP 1 LAST COMMENT_BODY TRUE
J 0
(1625 -500);
DISPLAY 1.170213 (1625 -500);
PAINT GREEN (1625 -500);
DISPLAY INVISIBLE (1625 -500);
FORCEPROP 1 LAST OFFPAGE TRUE
J 0
(1825 -525);
DISPLAY 0.872340 (1825 -525);
DISPLAY INVISIBLE (1825 -525);
FORCEADD OFFPAGE..1
(1500 -275);
FORCEPROP 2 LAST $XR0 148 
J 0
(1218 -275);
DISPLAY 0.638298 (1218 -275);
PAINT MONO (1218 -275);
FORCEPROP 2 LAST PATH I103
J 0
(1225 -225);
DISPLAY 1.021277 (1225 -225);
DISPLAY INVISIBLE (1225 -225);
FORCEPROP 1 LAST COMMENT_BODY TRUE
J 0
(1625 -375);
DISPLAY 1.170213 (1625 -375);
PAINT GREEN (1625 -375);
DISPLAY INVISIBLE (1625 -375);
FORCEPROP 1 LAST OFFPAGE TRUE
J 0
(1825 -400);
DISPLAY 0.872340 (1825 -400);
DISPLAY INVISIBLE (1825 -400);
FORCEPROP 2 LAST CDS_LIB standard
J 0
(1500 -275);
DISPLAY INVISIBLE (1500 -275);
FORCEADD OFFPAGE..1
(1500 -150);
FORCEPROP 2 LAST $XR0 213 
J 0
(1218 -150);
DISPLAY 0.638298 (1218 -150);
PAINT MONO (1218 -150);
FORCEPROP 2 LAST PATH I104
J 0
(1225 -100);
DISPLAY 1.021277 (1225 -100);
DISPLAY INVISIBLE (1225 -100);
FORCEPROP 2 LAST CDS_LIB standard
J 0
(1500 -150);
DISPLAY INVISIBLE (1500 -150);
FORCEPROP 1 LAST COMMENT_BODY TRUE
J 0
(1625 -250);
DISPLAY 1.170213 (1625 -250);
PAINT GREEN (1625 -250);
DISPLAY INVISIBLE (1625 -250);
FORCEPROP 1 LAST OFFPAGE TRUE
J 0
(1825 -275);
DISPLAY 0.872340 (1825 -275);
DISPLAY INVISIBLE (1825 -275);
FORCEADD OFFPAGE..1
(1500 -25);
FORCEPROP 2 LAST $XR0 213 
J 0
(1218 -25);
DISPLAY 0.638298 (1218 -25);
PAINT MONO (1218 -25);
FORCEPROP 2 LAST PATH I105
J 0
(1225 25);
DISPLAY 1.021277 (1225 25);
DISPLAY INVISIBLE (1225 25);
FORCEPROP 1 LAST COMMENT_BODY TRUE
J 0
(1625 -125);
DISPLAY 1.170213 (1625 -125);
PAINT GREEN (1625 -125);
DISPLAY INVISIBLE (1625 -125);
FORCEPROP 1 LAST OFFPAGE TRUE
J 0
(1825 -150);
DISPLAY 0.872340 (1825 -150);
DISPLAY INVISIBLE (1825 -150);
FORCEPROP 2 LAST CDS_LIB standard
J 0
(1500 -25);
DISPLAY INVISIBLE (1500 -25);
FORCEADD Q_RES..1
(2725 -1400);
FORCEPROP 1 LAST PART_NUMBER CS03322FB03
J 0
(2575 -1325);
DISPLAY 0.638298 (2575 -1325);
DISPLAY INVISIBLE (2575 -1325);
FORCEPROP 1 LAST VALUE 33.2
J 2
(2975 -1400);
DISPLAY 0.638298 (2975 -1400);
FORCEPROP 1 LAST MATERIAL CHIP
J 0
(3000 -1400);
DISPLAY 0.638298 (3000 -1400);
FORCEPROP 1 LAST LOCATION R2939
J 0
(2475 -1400);
DISPLAY 0.638298 (2475 -1400);
FORCEPROP 1 LASTPIN (2625 -1400) $PN 1
J 0
(2637 -1388);
DISPLAY 0.787234 (2637 -1388);
PAINT MONO (2637 -1388);
FORCEPROP 1 LASTPIN (2825 -1400) $PN 2
J 0
(2787 -1388);
DISPLAY 0.787234 (2787 -1388);
PAINT MONO (2787 -1388);
FORCEPROP 1 LAST PATH I106
J 0
(2675 -1250);
DISPLAY 0.978723 (2675 -1250);
PAINT WHITE (2675 -1250);
DISPLAY INVISIBLE (2675 -1250);
FORCEPROP 2 LAST CDS_LIB pure_quanta
J 0
(2725 -1400);
DISPLAY INVISIBLE (2725 -1400);
FORCEPROP 1 LAST TOLERANCE 1%
J 0
(3000 -1400);
DISPLAY 0.638298 (3000 -1400);
DISPLAY INVISIBLE (3000 -1400);
FORCEPROP 1 LAST PACK_TYPE 0402LF
J 0
(2575 -1275);
DISPLAY 0.638298 (2575 -1275);
DISPLAY INVISIBLE (2575 -1275);
FORCEPROP 1 LAST WATTAGE 1/16W
J 2
(2925 -1275);
DISPLAY 0.638298 (2925 -1275);
DISPLAY INVISIBLE (2925 -1275);
FORCEPROP 0 LAST $SEC 1
J 0
(3000 -1350);
DISPLAY 0.680851 (3000 -1350);
PAINT MONO (3000 -1350);
DISPLAY INVISIBLE (3000 -1350);
FORCEPROP 0 LAST CDS_SEC 1
J 0
(3000 -1350);
DISPLAY 1.021277 (3000 -1350);
DISPLAY INVISIBLE (3000 -1350);
FORCEADD Q_RES..1
(2725 -1225);
FORCEPROP 1 LAST PART_NUMBER CS03322FB03
J 0
(2575 -1150);
DISPLAY 0.638298 (2575 -1150);
DISPLAY INVISIBLE (2575 -1150);
FORCEPROP 1 LAST MATERIAL CHIP
J 0
(3000 -1225);
DISPLAY 0.638298 (3000 -1225);
FORCEPROP 1 LAST VALUE 33.2
J 2
(2975 -1225);
DISPLAY 0.638298 (2975 -1225);
FORCEPROP 1 LAST LOCATION R2847
J 0
(2475 -1225);
DISPLAY 0.638298 (2475 -1225);
FORCEPROP 1 LASTPIN (2625 -1225) $PN 1
J 0
(2637 -1213);
DISPLAY 0.787234 (2637 -1213);
PAINT MONO (2637 -1213);
FORCEPROP 1 LASTPIN (2825 -1225) $PN 2
J 0
(2787 -1213);
DISPLAY 0.787234 (2787 -1213);
PAINT MONO (2787 -1213);
FORCEPROP 1 LAST PATH I107
J 0
(2675 -1075);
DISPLAY 0.978723 (2675 -1075);
PAINT WHITE (2675 -1075);
DISPLAY INVISIBLE (2675 -1075);
FORCEPROP 2 LAST CDS_LIB pure_quanta
J 0
(2725 -1225);
DISPLAY INVISIBLE (2725 -1225);
FORCEPROP 1 LAST TOLERANCE 1%
J 0
(3000 -1225);
DISPLAY 0.638298 (3000 -1225);
DISPLAY INVISIBLE (3000 -1225);
FORCEPROP 1 LAST PACK_TYPE 0402LF
J 0
(2575 -1100);
DISPLAY 0.638298 (2575 -1100);
DISPLAY INVISIBLE (2575 -1100);
FORCEPROP 1 LAST WATTAGE 1/16W
J 2
(2925 -1100);
DISPLAY 0.638298 (2925 -1100);
DISPLAY INVISIBLE (2925 -1100);
FORCEPROP 0 LAST $SEC 1
J 0
(3000 -1175);
DISPLAY 0.680851 (3000 -1175);
PAINT MONO (3000 -1175);
DISPLAY INVISIBLE (3000 -1175);
FORCEPROP 0 LAST CDS_SEC 1
J 0
(3000 -1175);
DISPLAY 1.021277 (3000 -1175);
DISPLAY INVISIBLE (3000 -1175);
FORCEADD Q_RES..1
(2725 -1050);
FORCEPROP 1 LAST PART_NUMBER CS03322FB03
J 0
(2575 -975);
DISPLAY 0.638298 (2575 -975);
DISPLAY INVISIBLE (2575 -975);
FORCEPROP 1 LAST VALUE 33.2
J 2
(2975 -1050);
DISPLAY 0.638298 (2975 -1050);
FORCEPROP 1 LAST MATERIAL CHIP
J 0
(3000 -1050);
DISPLAY 0.638298 (3000 -1050);
FORCEPROP 1 LAST LOCATION R3324
J 0
(2475 -1050);
DISPLAY 0.638298 (2475 -1050);
FORCEPROP 1 LASTPIN (2625 -1050) $PN 1
J 0
(2637 -1038);
DISPLAY 0.787234 (2637 -1038);
PAINT MONO (2637 -1038);
FORCEPROP 1 LASTPIN (2825 -1050) $PN 2
J 0
(2787 -1038);
DISPLAY 0.787234 (2787 -1038);
PAINT MONO (2787 -1038);
FORCEPROP 1 LAST PATH I108
J 0
(2675 -900);
DISPLAY 0.978723 (2675 -900);
PAINT WHITE (2675 -900);
DISPLAY INVISIBLE (2675 -900);
FORCEPROP 1 LAST TOLERANCE 1%
J 0
(3000 -1050);
DISPLAY 0.638298 (3000 -1050);
DISPLAY INVISIBLE (3000 -1050);
FORCEPROP 1 LAST PACK_TYPE 0402LF
J 0
(2575 -925);
DISPLAY 0.638298 (2575 -925);
DISPLAY INVISIBLE (2575 -925);
FORCEPROP 1 LAST WATTAGE 1/16W
J 2
(2925 -925);
DISPLAY 0.638298 (2925 -925);
DISPLAY INVISIBLE (2925 -925);
FORCEPROP 2 LAST CDS_LIB pure_quanta
J 0
(2725 -1050);
DISPLAY INVISIBLE (2725 -1050);
FORCEPROP 0 LAST $SEC 1
J 0
(3000 -1000);
DISPLAY 0.680851 (3000 -1000);
PAINT MONO (3000 -1000);
DISPLAY INVISIBLE (3000 -1000);
FORCEPROP 0 LAST CDS_SEC 1
J 0
(3000 -1000);
DISPLAY 1.021277 (3000 -1000);
DISPLAY INVISIBLE (3000 -1000);
FORCEADD Q_RES..1
(2725 -925);
FORCEPROP 1 LAST PART_NUMBER CS03322FB03
J 0
(2575 -850);
DISPLAY 0.638298 (2575 -850);
DISPLAY INVISIBLE (2575 -850);
FORCEPROP 1 LAST VALUE 33.2
J 2
(2975 -925);
DISPLAY 0.638298 (2975 -925);
FORCEPROP 1 LAST MATERIAL CHIP
J 0
(3000 -925);
DISPLAY 0.638298 (3000 -925);
FORCEPROP 1 LAST LOCATION R1606
J 0
(2475 -925);
DISPLAY 0.638298 (2475 -925);
FORCEPROP 1 LASTPIN (2625 -925) $PN 1
J 0
(2637 -913);
DISPLAY 0.787234 (2637 -913);
PAINT MONO (2637 -913);
FORCEPROP 1 LASTPIN (2825 -925) $PN 2
J 0
(2787 -913);
DISPLAY 0.787234 (2787 -913);
PAINT MONO (2787 -913);
FORCEPROP 1 LAST PATH I109
J 0
(2675 -775);
DISPLAY 0.978723 (2675 -775);
PAINT WHITE (2675 -775);
DISPLAY INVISIBLE (2675 -775);
FORCEPROP 2 LAST CDS_LIB pure_quanta
J 0
(2725 -925);
DISPLAY INVISIBLE (2725 -925);
FORCEPROP 1 LAST WATTAGE 1/16W
J 2
(2925 -800);
DISPLAY 0.638298 (2925 -800);
DISPLAY INVISIBLE (2925 -800);
FORCEPROP 1 LAST PACK_TYPE 0402LF
J 0
(2575 -800);
DISPLAY 0.638298 (2575 -800);
DISPLAY INVISIBLE (2575 -800);
FORCEPROP 1 LAST TOLERANCE 1%
J 0
(3000 -925);
DISPLAY 0.638298 (3000 -925);
DISPLAY INVISIBLE (3000 -925);
FORCEPROP 0 LAST $SEC 1
J 0
(3000 -875);
DISPLAY 0.680851 (3000 -875);
PAINT MONO (3000 -875);
DISPLAY INVISIBLE (3000 -875);
FORCEPROP 0 LAST CDS_SEC 1
J 0
(3000 -875);
DISPLAY 1.021277 (3000 -875);
DISPLAY INVISIBLE (3000 -875);
FORCEADD OFFPAGE..2
R 2
(-3425 -500);
FORCEPROP 2 LAST $XR0 149 
J 0
(-3680 -500);
DISPLAY 0.638298 (-3680 -500);
PAINT MONO (-3680 -500);
FORCEPROP 2 LAST PATH I11
J 0
(-3675 -450);
DISPLAY 1.021277 (-3675 -450);
DISPLAY INVISIBLE (-3675 -450);
FORCEPROP 1 LAST COMMENT_BODY TRUE
J 2
(-3380 -595);
DISPLAY 1.170213 (-3380 -595);
PAINT GREEN (-3380 -595);
DISPLAY INVISIBLE (-3380 -595);
FORCEPROP 1 LAST OFFPAGE TRUE
J 2
(-3750 -625);
DISPLAY 1.170213 (-3750 -625);
PAINT GREEN (-3750 -625);
DISPLAY INVISIBLE (-3750 -625);
FORCEPROP 2 LAST CDS_LIB standard
J 0
(-3425 -500);
DISPLAY INVISIBLE (-3425 -500);
FORCEADD Q_RES..1
(2725 -775);
FORCEPROP 1 LAST PART_NUMBER CS03322FB03
J 0
(2575 -700);
DISPLAY 0.638298 (2575 -700);
DISPLAY INVISIBLE (2575 -700);
FORCEPROP 1 LAST VALUE 33.2
J 2
(2975 -775);
DISPLAY 0.638298 (2975 -775);
FORCEPROP 1 LAST MATERIAL CHIP
J 0
(3000 -775);
DISPLAY 0.638298 (3000 -775);
FORCEPROP 1 LAST LOCATION R3230
J 0
(2475 -775);
DISPLAY 0.638298 (2475 -775);
FORCEPROP 1 LASTPIN (2625 -775) $PN 1
J 0
(2637 -763);
DISPLAY 0.787234 (2637 -763);
PAINT MONO (2637 -763);
FORCEPROP 1 LASTPIN (2825 -775) $PN 2
J 0
(2787 -763);
DISPLAY 0.787234 (2787 -763);
PAINT MONO (2787 -763);
FORCEPROP 1 LAST PATH I110
J 0
(2675 -625);
DISPLAY 0.978723 (2675 -625);
PAINT WHITE (2675 -625);
DISPLAY INVISIBLE (2675 -625);
FORCEPROP 2 LAST CDS_LIB pure_quanta
J 0
(2725 -775);
DISPLAY INVISIBLE (2725 -775);
FORCEPROP 1 LAST WATTAGE 1/16W
J 2
(2925 -650);
DISPLAY 0.638298 (2925 -650);
DISPLAY INVISIBLE (2925 -650);
FORCEPROP 1 LAST PACK_TYPE 0402LF
J 0
(2575 -650);
DISPLAY 0.638298 (2575 -650);
DISPLAY INVISIBLE (2575 -650);
FORCEPROP 1 LAST TOLERANCE 1%
J 0
(3000 -775);
DISPLAY 0.638298 (3000 -775);
DISPLAY INVISIBLE (3000 -775);
FORCEPROP 0 LAST $SEC 1
J 0
(3000 -725);
DISPLAY 0.680851 (3000 -725);
PAINT MONO (3000 -725);
DISPLAY INVISIBLE (3000 -725);
FORCEPROP 0 LAST CDS_SEC 1
J 0
(3000 -725);
DISPLAY 1.021277 (3000 -725);
DISPLAY INVISIBLE (3000 -725);
FORCEADD Q_RES..1
(2725 -650);
FORCEPROP 1 LAST PART_NUMBER CS03322FB03
J 0
(2575 -575);
DISPLAY 0.638298 (2575 -575);
DISPLAY INVISIBLE (2575 -575);
FORCEPROP 1 LAST VALUE 33.2
J 2
(2975 -650);
DISPLAY 0.638298 (2975 -650);
FORCEPROP 1 LAST MATERIAL CHIP
J 0
(3000 -650);
DISPLAY 0.638298 (3000 -650);
FORCEPROP 1 LAST LOCATION R3043
J 0
(2475 -650);
DISPLAY 0.638298 (2475 -650);
FORCEPROP 1 LASTPIN (2625 -650) $PN 1
J 0
(2637 -638);
DISPLAY 0.787234 (2637 -638);
PAINT MONO (2637 -638);
FORCEPROP 1 LASTPIN (2825 -650) $PN 2
J 0
(2787 -638);
DISPLAY 0.787234 (2787 -638);
PAINT MONO (2787 -638);
FORCEPROP 1 LAST PATH I111
J 0
(2675 -500);
DISPLAY 0.978723 (2675 -500);
PAINT WHITE (2675 -500);
DISPLAY INVISIBLE (2675 -500);
FORCEPROP 2 LAST CDS_LIB pure_quanta
J 0
(2725 -650);
DISPLAY INVISIBLE (2725 -650);
FORCEPROP 1 LAST WATTAGE 1/16W
J 2
(2925 -525);
DISPLAY 0.638298 (2925 -525);
DISPLAY INVISIBLE (2925 -525);
FORCEPROP 1 LAST PACK_TYPE 0402LF
J 0
(2575 -525);
DISPLAY 0.638298 (2575 -525);
DISPLAY INVISIBLE (2575 -525);
FORCEPROP 1 LAST TOLERANCE 1%
J 0
(3000 -650);
DISPLAY 0.638298 (3000 -650);
DISPLAY INVISIBLE (3000 -650);
FORCEPROP 0 LAST $SEC 1
J 0
(3000 -600);
DISPLAY 0.680851 (3000 -600);
PAINT MONO (3000 -600);
DISPLAY INVISIBLE (3000 -600);
FORCEPROP 0 LAST CDS_SEC 1
J 0
(3000 -600);
DISPLAY 1.021277 (3000 -600);
DISPLAY INVISIBLE (3000 -600);
FORCEADD Q_RES..1
(2725 -525);
FORCEPROP 1 LAST PART_NUMBER CS03322FB03
J 0
(2575 -450);
DISPLAY 0.638298 (2575 -450);
DISPLAY INVISIBLE (2575 -450);
FORCEPROP 1 LAST VALUE 33.2
J 2
(2975 -525);
DISPLAY 0.638298 (2975 -525);
FORCEPROP 1 LAST MATERIAL CHIP
J 0
(3000 -525);
DISPLAY 0.638298 (3000 -525);
FORCEPROP 1 LAST LOCATION R2844
J 0
(2475 -525);
DISPLAY 0.638298 (2475 -525);
FORCEPROP 1 LASTPIN (2625 -525) $PN 1
J 0
(2637 -513);
DISPLAY 0.787234 (2637 -513);
PAINT MONO (2637 -513);
FORCEPROP 1 LASTPIN (2825 -525) $PN 2
J 0
(2787 -513);
DISPLAY 0.787234 (2787 -513);
PAINT MONO (2787 -513);
FORCEPROP 1 LAST PATH I112
J 0
(2675 -375);
DISPLAY 0.978723 (2675 -375);
PAINT WHITE (2675 -375);
DISPLAY INVISIBLE (2675 -375);
FORCEPROP 1 LAST TOLERANCE 1%
J 0
(3000 -525);
DISPLAY 0.638298 (3000 -525);
DISPLAY INVISIBLE (3000 -525);
FORCEPROP 1 LAST PACK_TYPE 0402LF
J 0
(2575 -400);
DISPLAY 0.638298 (2575 -400);
DISPLAY INVISIBLE (2575 -400);
FORCEPROP 1 LAST WATTAGE 1/16W
J 2
(2925 -400);
DISPLAY 0.638298 (2925 -400);
DISPLAY INVISIBLE (2925 -400);
FORCEPROP 2 LAST CDS_LIB pure_quanta
J 0
(2725 -525);
DISPLAY INVISIBLE (2725 -525);
FORCEPROP 0 LAST $SEC 1
J 0
(3000 -475);
DISPLAY 0.680851 (3000 -475);
PAINT MONO (3000 -475);
DISPLAY INVISIBLE (3000 -475);
FORCEPROP 0 LAST CDS_SEC 1
J 0
(3000 -475);
DISPLAY 1.021277 (3000 -475);
DISPLAY INVISIBLE (3000 -475);
FORCEADD Q_RES..1
(2725 -400);
FORCEPROP 1 LAST PART_NUMBER CS03322FB03
J 0
(2575 -325);
DISPLAY 0.638298 (2575 -325);
DISPLAY INVISIBLE (2575 -325);
FORCEPROP 1 LAST VALUE 33.2
J 2
(2975 -400);
DISPLAY 0.638298 (2975 -400);
FORCEPROP 1 LAST MATERIAL CHIP
J 0
(3000 -400);
DISPLAY 0.638298 (3000 -400);
FORCEPROP 1 LAST LOCATION R2664
J 0
(2475 -400);
DISPLAY 0.638298 (2475 -400);
FORCEPROP 1 LASTPIN (2625 -400) $PN 1
J 0
(2637 -388);
DISPLAY 0.787234 (2637 -388);
PAINT MONO (2637 -388);
FORCEPROP 1 LASTPIN (2825 -400) $PN 2
J 0
(2787 -388);
DISPLAY 0.787234 (2787 -388);
PAINT MONO (2787 -388);
FORCEPROP 1 LAST PATH I113
J 0
(2675 -250);
DISPLAY 0.978723 (2675 -250);
PAINT WHITE (2675 -250);
DISPLAY INVISIBLE (2675 -250);
FORCEPROP 2 LAST CDS_LIB pure_quanta
J 0
(2725 -400);
DISPLAY INVISIBLE (2725 -400);
FORCEPROP 1 LAST WATTAGE 1/16W
J 2
(2925 -275);
DISPLAY 0.638298 (2925 -275);
DISPLAY INVISIBLE (2925 -275);
FORCEPROP 1 LAST PACK_TYPE 0402LF
J 0
(2575 -275);
DISPLAY 0.638298 (2575 -275);
DISPLAY INVISIBLE (2575 -275);
FORCEPROP 1 LAST TOLERANCE 1%
J 0
(3000 -400);
DISPLAY 0.638298 (3000 -400);
DISPLAY INVISIBLE (3000 -400);
FORCEPROP 0 LAST $SEC 1
J 0
(3000 -350);
DISPLAY 0.680851 (3000 -350);
PAINT MONO (3000 -350);
DISPLAY INVISIBLE (3000 -350);
FORCEPROP 0 LAST CDS_SEC 1
J 0
(3000 -350);
DISPLAY 1.021277 (3000 -350);
DISPLAY INVISIBLE (3000 -350);
FORCEADD Q_RES..1
(2725 -275);
FORCEPROP 1 LAST PART_NUMBER CS03322FB03
J 0
(2575 -200);
DISPLAY 0.638298 (2575 -200);
DISPLAY INVISIBLE (2575 -200);
FORCEPROP 1 LAST MATERIAL CHIP
J 0
(3000 -275);
DISPLAY 0.638298 (3000 -275);
FORCEPROP 1 LAST VALUE 33.2
J 2
(2975 -275);
DISPLAY 0.638298 (2975 -275);
FORCEPROP 1 LAST LOCATION R2663
J 0
(2475 -275);
DISPLAY 0.638298 (2475 -275);
FORCEPROP 1 LASTPIN (2625 -275) $PN 1
J 0
(2637 -263);
DISPLAY 0.787234 (2637 -263);
PAINT MONO (2637 -263);
FORCEPROP 1 LASTPIN (2825 -275) $PN 2
J 0
(2787 -263);
DISPLAY 0.787234 (2787 -263);
PAINT MONO (2787 -263);
FORCEPROP 1 LAST PATH I114
J 0
(2675 -125);
DISPLAY 0.978723 (2675 -125);
PAINT WHITE (2675 -125);
DISPLAY INVISIBLE (2675 -125);
FORCEPROP 2 LAST CDS_LIB pure_quanta
J 0
(2725 -275);
DISPLAY INVISIBLE (2725 -275);
FORCEPROP 1 LAST WATTAGE 1/16W
J 2
(2925 -150);
DISPLAY 0.638298 (2925 -150);
DISPLAY INVISIBLE (2925 -150);
FORCEPROP 1 LAST PACK_TYPE 0402LF
J 0
(2575 -150);
DISPLAY 0.638298 (2575 -150);
DISPLAY INVISIBLE (2575 -150);
FORCEPROP 1 LAST TOLERANCE 1%
J 0
(3000 -275);
DISPLAY 0.638298 (3000 -275);
DISPLAY INVISIBLE (3000 -275);
FORCEPROP 0 LAST $SEC 1
J 0
(3000 -225);
DISPLAY 0.680851 (3000 -225);
PAINT MONO (3000 -225);
DISPLAY INVISIBLE (3000 -225);
FORCEPROP 0 LAST CDS_SEC 1
J 0
(3000 -225);
DISPLAY 1.021277 (3000 -225);
DISPLAY INVISIBLE (3000 -225);
FORCEADD Q_RES..1
(2725 -150);
FORCEPROP 1 LAST PART_NUMBER CS03322FB03
J 0
(2575 -75);
DISPLAY 0.638298 (2575 -75);
DISPLAY INVISIBLE (2575 -75);
FORCEPROP 1 LAST VALUE 33.2
J 2
(2975 -150);
DISPLAY 0.638298 (2975 -150);
FORCEPROP 1 LAST MATERIAL CHIP
J 0
(3000 -150);
DISPLAY 0.638298 (3000 -150);
FORCEPROP 1 LAST LOCATION R2662
J 0
(2475 -150);
DISPLAY 0.638298 (2475 -150);
FORCEPROP 1 LASTPIN (2625 -150) $PN 1
J 0
(2637 -138);
DISPLAY 0.787234 (2637 -138);
PAINT MONO (2637 -138);
FORCEPROP 1 LASTPIN (2825 -150) $PN 2
J 0
(2787 -138);
DISPLAY 0.787234 (2787 -138);
PAINT MONO (2787 -138);
FORCEPROP 1 LAST PATH I115
J 0
(2675 0);
DISPLAY 0.978723 (2675 0);
PAINT WHITE (2675 0);
DISPLAY INVISIBLE (2675 0);
FORCEPROP 2 LAST CDS_LIB pure_quanta
J 0
(2725 -150);
DISPLAY INVISIBLE (2725 -150);
FORCEPROP 1 LAST TOLERANCE 1%
J 0
(3000 -150);
DISPLAY 0.638298 (3000 -150);
DISPLAY INVISIBLE (3000 -150);
FORCEPROP 1 LAST PACK_TYPE 0402LF
J 0
(2575 -25);
DISPLAY 0.638298 (2575 -25);
DISPLAY INVISIBLE (2575 -25);
FORCEPROP 1 LAST WATTAGE 1/16W
J 2
(2925 -25);
DISPLAY 0.638298 (2925 -25);
DISPLAY INVISIBLE (2925 -25);
FORCEPROP 0 LAST $SEC 1
J 0
(3000 -100);
DISPLAY 0.680851 (3000 -100);
PAINT MONO (3000 -100);
DISPLAY INVISIBLE (3000 -100);
FORCEPROP 0 LAST CDS_SEC 1
J 0
(3000 -100);
DISPLAY 1.021277 (3000 -100);
DISPLAY INVISIBLE (3000 -100);
FORCEADD OFFPAGE..2
(3950 -1400);
FORCEPROP 2 LAST $XR0 246 
J 0
(4139 -1400);
DISPLAY 0.638298 (4139 -1400);
PAINT MONO (4139 -1400);
FORCEPROP 2 LAST PATH I116
J 0
(4150 -1350);
DISPLAY 1.021277 (4150 -1350);
DISPLAY INVISIBLE (4150 -1350);
FORCEPROP 2 LAST CDS_LIB standard
J 0
(3950 -1400);
DISPLAY INVISIBLE (3950 -1400);
FORCEPROP 1 LAST OFFPAGE TRUE
J 0
(4275 -1525);
DISPLAY 0.872340 (4275 -1525);
PAINT GREEN (4275 -1525);
DISPLAY INVISIBLE (4275 -1525);
FORCEPROP 1 LAST COMMENT_BODY TRUE
J 0
(3905 -1495);
DISPLAY 0.872340 (3905 -1495);
PAINT PEACH (3905 -1495);
DISPLAY INVISIBLE (3905 -1495);
FORCEADD OFFPAGE..2
(3950 -1225);
FORCEPROP 2 LAST $XR0 213 
J 0
(4139 -1225);
DISPLAY 0.638298 (4139 -1225);
PAINT MONO (4139 -1225);
FORCEPROP 2 LAST PATH I117
J 0
(4150 -1175);
DISPLAY 1.021277 (4150 -1175);
DISPLAY INVISIBLE (4150 -1175);
FORCEPROP 1 LAST COMMENT_BODY TRUE
J 0
(3905 -1320);
DISPLAY 0.872340 (3905 -1320);
PAINT PEACH (3905 -1320);
DISPLAY INVISIBLE (3905 -1320);
FORCEPROP 1 LAST OFFPAGE TRUE
J 0
(4275 -1350);
DISPLAY 0.872340 (4275 -1350);
PAINT GREEN (4275 -1350);
DISPLAY INVISIBLE (4275 -1350);
FORCEPROP 2 LAST CDS_LIB standard
J 0
(3950 -1225);
DISPLAY INVISIBLE (3950 -1225);
FORCEADD OFFPAGE..2
(3950 -1050);
FORCEPROP 2 LAST $XR0 213 
J 0
(4139 -1050);
DISPLAY 0.638298 (4139 -1050);
PAINT MONO (4139 -1050);
FORCEPROP 2 LAST PATH I118
J 0
(4150 -1000);
DISPLAY 1.021277 (4150 -1000);
DISPLAY INVISIBLE (4150 -1000);
FORCEPROP 1 LAST OFFPAGE TRUE
J 0
(4275 -1175);
DISPLAY 1.170213 (4275 -1175);
PAINT GREEN (4275 -1175);
DISPLAY INVISIBLE (4275 -1175);
FORCEPROP 1 LAST COMMENT_BODY TRUE
J 0
(3905 -1145);
DISPLAY 1.170213 (3905 -1145);
PAINT GREEN (3905 -1145);
DISPLAY INVISIBLE (3905 -1145);
FORCEPROP 2 LAST CDS_LIB standard
J 0
(3950 -1050);
DISPLAY INVISIBLE (3950 -1050);
FORCEADD OFFPAGE..2
(3950 -925);
FORCEPROP 2 LAST $XR0 213 
J 0
(4139 -925);
DISPLAY 0.638298 (4139 -925);
PAINT MONO (4139 -925);
FORCEPROP 2 LAST PATH I119
J 0
(4150 -875);
DISPLAY 1.021277 (4150 -875);
DISPLAY INVISIBLE (4150 -875);
FORCEPROP 2 LAST CDS_LIB standard
J 0
(3950 -925);
DISPLAY INVISIBLE (3950 -925);
FORCEPROP 1 LAST COMMENT_BODY TRUE
J 0
(3905 -1020);
DISPLAY 1.170213 (3905 -1020);
PAINT GREEN (3905 -1020);
DISPLAY INVISIBLE (3905 -1020);
FORCEPROP 1 LAST OFFPAGE TRUE
J 0
(4275 -1050);
DISPLAY 1.170213 (4275 -1050);
PAINT GREEN (4275 -1050);
DISPLAY INVISIBLE (4275 -1050);
FORCEADD OFFPAGE..2
R 2
(-3425 -375);
FORCEPROP 2 LAST $XR0 150 
J 0
(-3680 -375);
DISPLAY 0.638298 (-3680 -375);
PAINT MONO (-3680 -375);
FORCEPROP 2 LAST PATH I12
J 0
(-3675 -325);
DISPLAY 1.021277 (-3675 -325);
DISPLAY INVISIBLE (-3675 -325);
FORCEPROP 1 LAST COMMENT_BODY TRUE
J 2
(-3380 -470);
DISPLAY 1.170213 (-3380 -470);
PAINT GREEN (-3380 -470);
DISPLAY INVISIBLE (-3380 -470);
FORCEPROP 1 LAST OFFPAGE TRUE
J 2
(-3750 -500);
DISPLAY 1.170213 (-3750 -500);
PAINT GREEN (-3750 -500);
DISPLAY INVISIBLE (-3750 -500);
FORCEPROP 2 LAST CDS_LIB standard
J 0
(-3425 -375);
DISPLAY INVISIBLE (-3425 -375);
FORCEADD OFFPAGE..2
(3950 -775);
FORCEPROP 2 LAST $XR0 213 
J 0
(4139 -775);
DISPLAY 0.638298 (4139 -775);
PAINT MONO (4139 -775);
FORCEPROP 2 LAST PATH I120
J 0
(4150 -725);
DISPLAY 1.021277 (4150 -725);
DISPLAY INVISIBLE (4150 -725);
FORCEPROP 1 LAST OFFPAGE TRUE
J 0
(4275 -900);
DISPLAY 1.170213 (4275 -900);
PAINT GREEN (4275 -900);
DISPLAY INVISIBLE (4275 -900);
FORCEPROP 1 LAST COMMENT_BODY TRUE
J 0
(3905 -870);
DISPLAY 1.170213 (3905 -870);
PAINT GREEN (3905 -870);
DISPLAY INVISIBLE (3905 -870);
FORCEPROP 2 LAST CDS_LIB standard
J 0
(3950 -775);
DISPLAY INVISIBLE (3950 -775);
FORCEADD OFFPAGE..2
(3950 -650);
FORCEPROP 2 LAST $XR0 213 
J 0
(4139 -650);
DISPLAY 0.638298 (4139 -650);
PAINT MONO (4139 -650);
FORCEPROP 2 LAST PATH I121
J 0
(4150 -600);
DISPLAY 1.021277 (4150 -600);
DISPLAY INVISIBLE (4150 -600);
FORCEPROP 2 LAST CDS_LIB standard
J 0
(3950 -650);
DISPLAY INVISIBLE (3950 -650);
FORCEPROP 1 LAST OFFPAGE TRUE
J 0
(4275 -775);
DISPLAY 0.872340 (4275 -775);
PAINT GREEN (4275 -775);
DISPLAY INVISIBLE (4275 -775);
FORCEPROP 1 LAST COMMENT_BODY TRUE
J 0
(3905 -745);
DISPLAY 0.872340 (3905 -745);
PAINT PEACH (3905 -745);
DISPLAY INVISIBLE (3905 -745);
FORCEADD OFFPAGE..2
(3950 -525);
FORCEPROP 2 LAST $XR0 213 
J 0
(4139 -525);
DISPLAY 0.638298 (4139 -525);
PAINT MONO (4139 -525);
FORCEPROP 2 LAST PATH I122
J 0
(4150 -475);
DISPLAY 1.021277 (4150 -475);
DISPLAY INVISIBLE (4150 -475);
FORCEPROP 2 LAST CDS_LIB standard
J 0
(3950 -525);
DISPLAY INVISIBLE (3950 -525);
FORCEPROP 1 LAST OFFPAGE TRUE
J 0
(4275 -650);
DISPLAY 0.872340 (4275 -650);
PAINT GREEN (4275 -650);
DISPLAY INVISIBLE (4275 -650);
FORCEPROP 1 LAST COMMENT_BODY TRUE
J 0
(3905 -620);
DISPLAY 0.872340 (3905 -620);
PAINT PEACH (3905 -620);
DISPLAY INVISIBLE (3905 -620);
FORCEADD OFFPAGE..2
(3950 -400);
FORCEPROP 2 LAST $XR0 213 
J 0
(4139 -400);
DISPLAY 0.638298 (4139 -400);
PAINT MONO (4139 -400);
FORCEPROP 2 LAST PATH I123
J 0
(4150 -350);
DISPLAY 1.021277 (4150 -350);
DISPLAY INVISIBLE (4150 -350);
FORCEPROP 2 LAST CDS_LIB standard
J 0
(3950 -400);
DISPLAY INVISIBLE (3950 -400);
FORCEPROP 1 LAST OFFPAGE TRUE
J 0
(4275 -525);
DISPLAY 0.872340 (4275 -525);
PAINT GREEN (4275 -525);
DISPLAY INVISIBLE (4275 -525);
FORCEPROP 1 LAST COMMENT_BODY TRUE
J 0
(3905 -495);
DISPLAY 0.872340 (3905 -495);
PAINT PEACH (3905 -495);
DISPLAY INVISIBLE (3905 -495);
FORCEADD OFFPAGE..2
(3950 -275);
FORCEPROP 2 LAST $XR0 213 
J 0
(4139 -275);
DISPLAY 0.638298 (4139 -275);
PAINT MONO (4139 -275);
FORCEPROP 2 LAST PATH I124
J 0
(4150 -225);
DISPLAY 1.021277 (4150 -225);
DISPLAY INVISIBLE (4150 -225);
FORCEPROP 1 LAST OFFPAGE TRUE
J 0
(4275 -400);
DISPLAY 0.872340 (4275 -400);
PAINT GREEN (4275 -400);
DISPLAY INVISIBLE (4275 -400);
FORCEPROP 1 LAST COMMENT_BODY TRUE
J 0
(3905 -370);
DISPLAY 0.872340 (3905 -370);
PAINT PEACH (3905 -370);
DISPLAY INVISIBLE (3905 -370);
FORCEPROP 2 LAST CDS_LIB standard
J 0
(3950 -275);
PAINT MONO (3950 -275);
DISPLAY INVISIBLE (3950 -275);
FORCEADD OFFPAGE..2
(3950 -150);
FORCEPROP 2 LAST $XR0 151 
J 0
(4139 -150);
DISPLAY 0.638298 (4139 -150);
PAINT MONO (4139 -150);
FORCEPROP 2 LAST PATH I125
J 0
(4150 -100);
DISPLAY 1.021277 (4150 -100);
DISPLAY INVISIBLE (4150 -100);
FORCEPROP 2 LAST CDS_LIB standard
J 0
(3950 -150);
PAINT MONO (3950 -150);
DISPLAY INVISIBLE (3950 -150);
FORCEPROP 1 LAST OFFPAGE TRUE
J 0
(4275 -275);
DISPLAY 0.872340 (4275 -275);
PAINT GREEN (4275 -275);
DISPLAY INVISIBLE (4275 -275);
FORCEPROP 1 LAST COMMENT_BODY TRUE
J 0
(3905 -245);
DISPLAY 0.872340 (3905 -245);
PAINT PEACH (3905 -245);
DISPLAY INVISIBLE (3905 -245);
FORCEADD OFFPAGE..2
(3950 -25);
FORCEPROP 2 LAST $XR0 149 
J 0
(4139 -25);
DISPLAY 0.638298 (4139 -25);
PAINT MONO (4139 -25);
FORCEPROP 2 LAST PATH I126
J 0
(4150 25);
DISPLAY 1.021277 (4150 25);
DISPLAY INVISIBLE (4150 25);
FORCEPROP 1 LAST COMMENT_BODY TRUE
J 0
(3905 -120);
DISPLAY 0.872340 (3905 -120);
PAINT PEACH (3905 -120);
DISPLAY INVISIBLE (3905 -120);
FORCEPROP 1 LAST OFFPAGE TRUE
J 0
(4275 -150);
DISPLAY 0.872340 (4275 -150);
PAINT GREEN (4275 -150);
DISPLAY INVISIBLE (4275 -150);
FORCEPROP 2 LAST CDS_LIB standard
J 0
(3950 -25);
PAINT MONO (3950 -25);
DISPLAY INVISIBLE (3950 -25);
FORCEADD OFFPAGE..1
(1500 125);
FORCEPROP 2 LAST $XR0 148 
J 0
(1218 125);
DISPLAY 0.638298 (1218 125);
PAINT MONO (1218 125);
FORCEPROP 2 LAST PATH I127
J 0
(1225 175);
DISPLAY 1.021277 (1225 175);
DISPLAY INVISIBLE (1225 175);
FORCEPROP 2 LAST CDS_LIB standard
J 0
(1500 125);
DISPLAY INVISIBLE (1500 125);
FORCEPROP 1 LAST OFFPAGE TRUE
J 0
(1825 0);
DISPLAY 0.872340 (1825 0);
DISPLAY INVISIBLE (1825 0);
FORCEPROP 1 LAST COMMENT_BODY TRUE
J 0
(1625 25);
DISPLAY 1.170213 (1625 25);
PAINT GREEN (1625 25);
DISPLAY INVISIBLE (1625 25);
FORCEADD OFFPAGE..1
(1500 300);
FORCEPROP 2 LAST $XR0 213 
J 0
(1218 300);
DISPLAY 0.638298 (1218 300);
PAINT MONO (1218 300);
FORCEPROP 2 LAST PATH I128
J 0
(1225 350);
DISPLAY 1.021277 (1225 350);
DISPLAY INVISIBLE (1225 350);
FORCEPROP 1 LAST COMMENT_BODY TRUE
J 0
(1625 200);
DISPLAY 1.170213 (1625 200);
PAINT GREEN (1625 200);
DISPLAY INVISIBLE (1625 200);
FORCEPROP 1 LAST OFFPAGE TRUE
J 0
(1825 175);
DISPLAY 0.872340 (1825 175);
DISPLAY INVISIBLE (1825 175);
FORCEPROP 2 LAST CDS_LIB standard
J 0
(1500 300);
DISPLAY INVISIBLE (1500 300);
FORCEADD OFFPAGE..1
(1500 450);
FORCEPROP 2 LAST $XR0 213 
J 0
(1218 450);
DISPLAY 0.638298 (1218 450);
PAINT MONO (1218 450);
FORCEPROP 2 LAST PATH I129
J 0
(1225 500);
DISPLAY 1.021277 (1225 500);
DISPLAY INVISIBLE (1225 500);
FORCEPROP 2 LAST CDS_LIB standard
J 0
(1500 450);
DISPLAY INVISIBLE (1500 450);
FORCEPROP 1 LAST OFFPAGE TRUE
J 0
(1825 325);
DISPLAY 0.872340 (1825 325);
DISPLAY INVISIBLE (1825 325);
FORCEPROP 1 LAST COMMENT_BODY TRUE
J 0
(1625 350);
DISPLAY 1.170213 (1625 350);
PAINT GREEN (1625 350);
DISPLAY INVISIBLE (1625 350);
FORCEADD OFFPAGE..2
R 2
(-3425 -250);
FORCEPROP 2 LAST $XR0 150 
J 0
(-3680 -250);
DISPLAY 0.638298 (-3680 -250);
PAINT MONO (-3680 -250);
FORCEPROP 2 LAST PATH I13
J 0
(-3675 -200);
DISPLAY 1.021277 (-3675 -200);
DISPLAY INVISIBLE (-3675 -200);
FORCEPROP 2 LAST CDS_LIB standard
J 2
(-3425 -250);
DISPLAY INVISIBLE (-3425 -250);
FORCEPROP 1 LAST COMMENT_BODY TRUE
J 2
(-3380 -345);
DISPLAY 1.170213 (-3380 -345);
PAINT GREEN (-3380 -345);
DISPLAY INVISIBLE (-3380 -345);
FORCEPROP 1 LAST OFFPAGE TRUE
J 2
(-3750 -375);
DISPLAY 1.170213 (-3750 -375);
PAINT GREEN (-3750 -375);
DISPLAY INVISIBLE (-3750 -375);
FORCEADD OFFPAGE..1
(1500 575);
FORCEPROP 2 LAST $XR0 213 
J 0
(1218 575);
DISPLAY 0.638298 (1218 575);
PAINT MONO (1218 575);
FORCEPROP 2 LAST PATH I130
J 0
(1225 625);
DISPLAY 1.021277 (1225 625);
DISPLAY INVISIBLE (1225 625);
FORCEPROP 1 LAST OFFPAGE TRUE
J 0
(1825 450);
DISPLAY 0.872340 (1825 450);
DISPLAY INVISIBLE (1825 450);
FORCEPROP 1 LAST COMMENT_BODY TRUE
J 0
(1625 475);
DISPLAY 1.170213 (1625 475);
PAINT GREEN (1625 475);
DISPLAY INVISIBLE (1625 475);
FORCEPROP 2 LAST CDS_LIB standard
J 0
(1500 575);
DISPLAY INVISIBLE (1500 575);
FORCEADD OFFPAGE..1
(1500 700);
FORCEPROP 2 LAST $XR0 213 
J 0
(1218 700);
DISPLAY 0.638298 (1218 700);
PAINT MONO (1218 700);
FORCEPROP 2 LAST PATH I131
J 0
(1225 750);
DISPLAY 1.021277 (1225 750);
DISPLAY INVISIBLE (1225 750);
FORCEPROP 1 LAST OFFPAGE TRUE
J 0
(1825 575);
DISPLAY 0.872340 (1825 575);
DISPLAY INVISIBLE (1825 575);
FORCEPROP 1 LAST COMMENT_BODY TRUE
J 0
(1625 600);
DISPLAY 1.170213 (1625 600);
PAINT GREEN (1625 600);
DISPLAY INVISIBLE (1625 600);
FORCEPROP 2 LAST CDS_LIB standard
J 0
(1500 700);
DISPLAY INVISIBLE (1500 700);
FORCEADD OFFPAGE..2
R 2
(1500 950);
FORCEPROP 2 LAST $XR0 248 
J 0
(1245 950);
DISPLAY 0.638298 (1245 950);
PAINT MONO (1245 950);
FORCEPROP 2 LAST PATH I132
J 0
(1250 1000);
DISPLAY 1.021277 (1250 1000);
DISPLAY INVISIBLE (1250 1000);
FORCEPROP 2 LAST CDS_LIB standard
J 2
(1500 950);
DISPLAY INVISIBLE (1500 950);
FORCEPROP 1 LAST COMMENT_BODY TRUE
J 2
(1545 855);
DISPLAY 0.872340 (1545 855);
PAINT PEACH (1545 855);
DISPLAY INVISIBLE (1545 855);
FORCEPROP 1 LAST OFFPAGE TRUE
J 2
(1175 825);
DISPLAY 0.872340 (1175 825);
PAINT GREEN (1175 825);
DISPLAY INVISIBLE (1175 825);
FORCEADD OFFPAGE..1
(1500 825);
FORCEPROP 2 LAST $XR0 213 
J 0
(1218 825);
DISPLAY 0.638298 (1218 825);
PAINT MONO (1218 825);
FORCEPROP 2 LAST PATH I133
J 0
(1225 875);
DISPLAY 1.021277 (1225 875);
DISPLAY INVISIBLE (1225 875);
FORCEPROP 2 LAST CDS_LIB standard
J 0
(1500 825);
DISPLAY INVISIBLE (1500 825);
FORCEPROP 1 LAST OFFPAGE TRUE
J 0
(1825 700);
DISPLAY 0.872340 (1825 700);
DISPLAY INVISIBLE (1825 700);
FORCEPROP 1 LAST COMMENT_BODY TRUE
J 0
(1625 725);
DISPLAY 1.170213 (1625 725);
PAINT GREEN (1625 725);
DISPLAY INVISIBLE (1625 725);
FORCEADD Q_RES..1
(2725 125);
FORCEPROP 1 LAST PART_NUMBER CS03322FB03
J 0
(2575 200);
DISPLAY 0.638298 (2575 200);
DISPLAY INVISIBLE (2575 200);
FORCEPROP 1 LAST VALUE 33.2
J 2
(2975 125);
DISPLAY 0.638298 (2975 125);
FORCEPROP 1 LAST MATERIAL CHIP
J 0
(3000 125);
DISPLAY 0.638298 (3000 125);
FORCEPROP 1 LAST LOCATION R2846
J 0
(2475 125);
DISPLAY 0.638298 (2475 125);
FORCEPROP 1 LASTPIN (2625 125) $PN 1
J 0
(2637 137);
DISPLAY 0.787234 (2637 137);
PAINT MONO (2637 137);
FORCEPROP 1 LASTPIN (2825 125) $PN 2
J 0
(2787 137);
DISPLAY 0.787234 (2787 137);
PAINT MONO (2787 137);
FORCEPROP 1 LAST PATH I134
J 0
(2675 275);
DISPLAY 0.978723 (2675 275);
PAINT WHITE (2675 275);
DISPLAY INVISIBLE (2675 275);
FORCEPROP 1 LAST TOLERANCE 1%
J 0
(3000 125);
DISPLAY 0.638298 (3000 125);
DISPLAY INVISIBLE (3000 125);
FORCEPROP 1 LAST PACK_TYPE 0402LF
J 0
(2575 250);
DISPLAY 0.638298 (2575 250);
DISPLAY INVISIBLE (2575 250);
FORCEPROP 1 LAST WATTAGE 1/16W
J 2
(2925 250);
DISPLAY 0.638298 (2925 250);
DISPLAY INVISIBLE (2925 250);
FORCEPROP 2 LAST CDS_LIB pure_quanta
J 0
(2725 125);
DISPLAY INVISIBLE (2725 125);
FORCEPROP 0 LAST $SEC 1
J 0
(3000 175);
DISPLAY 0.680851 (3000 175);
PAINT MONO (3000 175);
DISPLAY INVISIBLE (3000 175);
FORCEPROP 0 LAST CDS_SEC 1
J 0
(3000 175);
DISPLAY 1.021277 (3000 175);
DISPLAY INVISIBLE (3000 175);
FORCEADD Q_RES..1
(2725 -25);
FORCEPROP 1 LAST PART_NUMBER CS03322FB03
J 0
(2575 50);
DISPLAY 0.638298 (2575 50);
DISPLAY INVISIBLE (2575 50);
FORCEPROP 1 LAST MATERIAL CHIP
J 0
(3000 -25);
DISPLAY 0.638298 (3000 -25);
FORCEPROP 1 LAST VALUE 33.2
J 2
(2975 -25);
DISPLAY 0.638298 (2975 -25);
FORCEPROP 1 LAST LOCATION R2661
J 0
(2475 -25);
DISPLAY 0.638298 (2475 -25);
FORCEPROP 1 LASTPIN (2625 -25) $PN 1
J 0
(2637 -13);
DISPLAY 0.787234 (2637 -13);
PAINT MONO (2637 -13);
FORCEPROP 1 LASTPIN (2825 -25) $PN 2
J 0
(2787 -13);
DISPLAY 0.787234 (2787 -13);
PAINT MONO (2787 -13);
FORCEPROP 1 LAST PATH I135
J 0
(2675 125);
DISPLAY 0.978723 (2675 125);
PAINT WHITE (2675 125);
DISPLAY INVISIBLE (2675 125);
FORCEPROP 1 LAST WATTAGE 1/16W
J 2
(2925 100);
DISPLAY 0.638298 (2925 100);
DISPLAY INVISIBLE (2925 100);
FORCEPROP 1 LAST PACK_TYPE 0402LF
J 0
(2575 100);
DISPLAY 0.638298 (2575 100);
DISPLAY INVISIBLE (2575 100);
FORCEPROP 1 LAST TOLERANCE 1%
J 0
(3000 -25);
DISPLAY 0.638298 (3000 -25);
DISPLAY INVISIBLE (3000 -25);
FORCEPROP 2 LAST CDS_LIB pure_quanta
J 0
(2725 -25);
DISPLAY INVISIBLE (2725 -25);
FORCEPROP 0 LAST $SEC 1
J 0
(3000 25);
DISPLAY 0.680851 (3000 25);
PAINT MONO (3000 25);
DISPLAY INVISIBLE (3000 25);
FORCEPROP 0 LAST CDS_SEC 1
J 0
(3000 25);
DISPLAY 1.021277 (3000 25);
DISPLAY INVISIBLE (3000 25);
FORCEADD Q_RES..1
(2725 300);
FORCEPROP 1 LAST PART_NUMBER CS03322FB03
J 0
(2575 375);
DISPLAY 0.638298 (2575 375);
DISPLAY INVISIBLE (2575 375);
FORCEPROP 1 LAST VALUE 33.2
J 2
(2975 300);
DISPLAY 0.638298 (2975 300);
FORCEPROP 1 LAST MATERIAL CHIP
J 0
(3000 300);
DISPLAY 0.638298 (3000 300);
FORCEPROP 1 LAST LOCATION R2845
J 0
(2475 300);
DISPLAY 0.638298 (2475 300);
FORCEPROP 1 LASTPIN (2625 300) $PN 1
J 0
(2637 312);
DISPLAY 0.787234 (2637 312);
PAINT MONO (2637 312);
FORCEPROP 1 LASTPIN (2825 300) $PN 2
J 0
(2787 312);
DISPLAY 0.787234 (2787 312);
PAINT MONO (2787 312);
FORCEPROP 1 LAST PATH I136
J 0
(2675 450);
DISPLAY 0.978723 (2675 450);
PAINT WHITE (2675 450);
DISPLAY INVISIBLE (2675 450);
FORCEPROP 1 LAST TOLERANCE 1%
J 0
(3000 300);
DISPLAY 0.638298 (3000 300);
DISPLAY INVISIBLE (3000 300);
FORCEPROP 1 LAST PACK_TYPE 0402LF
J 0
(2575 425);
DISPLAY 0.638298 (2575 425);
DISPLAY INVISIBLE (2575 425);
FORCEPROP 1 LAST WATTAGE 1/16W
J 2
(2925 425);
DISPLAY 0.638298 (2925 425);
DISPLAY INVISIBLE (2925 425);
FORCEPROP 2 LAST CDS_LIB pure_quanta
J 0
(2725 300);
DISPLAY INVISIBLE (2725 300);
FORCEPROP 0 LAST $SEC 1
J 0
(3000 350);
DISPLAY 0.680851 (3000 350);
PAINT MONO (3000 350);
DISPLAY INVISIBLE (3000 350);
FORCEPROP 0 LAST CDS_SEC 1
J 0
(3000 350);
DISPLAY 1.021277 (3000 350);
DISPLAY INVISIBLE (3000 350);
FORCEADD Q_RES..1
(2725 450);
FORCEPROP 1 LAST PART_NUMBER CS00002JB13
J 0
(2675 500);
DISPLAY 0.404255 (2675 500);
DISPLAY INVISIBLE (2675 500);
FORCEPROP 1 LAST MATERIAL EMPTY
J 0
(2975 450);
DISPLAY 0.510638 (2975 450);
PAINT RED (2975 450);
FORCEPROP 1 LAST TOLERANCE 5%
J 0
(2900 450);
DISPLAY 0.510638 (2900 450);
FORCEPROP 1 LAST VALUE 0
J 2
(2875 450);
DISPLAY 0.510638 (2875 450);
FORCEPROP 1 LAST $LOCATION R2071
J 0
(2525 450);
DISPLAY 0.510638 (2525 450);
FORCEPROP 1 LASTPIN (2625 450) $PN 1
J 0
(2637 462);
DISPLAY 0.787234 (2637 462);
PAINT MONO (2637 462);
FORCEPROP 1 LASTPIN (2825 450) $PN 2
J 0
(2787 462);
DISPLAY 0.787234 (2787 462);
PAINT MONO (2787 462);
FORCEPROP 1 LAST PATH I137
J 0
(2675 600);
DISPLAY 0.978723 (2675 600);
PAINT WHITE (2675 600);
DISPLAY INVISIBLE (2675 600);
FORCEPROP 2 LAST CDS_LIB pure_quanta
J 0
(2725 450);
DISPLAY INVISIBLE (2725 450);
FORCEPROP 1 LAST PACK_TYPE 0402LF
J 0
(2975 450);
DISPLAY 0.510638 (2975 450);
DISPLAY INVISIBLE (2975 450);
FORCEPROP 1 LAST WATTAGE 1/16W
J 2
(2900 525);
DISPLAY 0.404255 (2900 525);
DISPLAY INVISIBLE (2900 525);
FORCEPROP 0 LAST CDS_LOCATION R2071
J 0
(2550 500);
DISPLAY 1.021277 (2550 500);
DISPLAY INVISIBLE (2550 500);
FORCEPROP 0 LAST $SEC 1
J 0
(2550 500);
DISPLAY 0.680851 (2550 500);
PAINT MONO (2550 500);
DISPLAY INVISIBLE (2550 500);
FORCEPROP 0 LAST CDS_SEC 1
J 0
(2550 500);
DISPLAY 1.021277 (2550 500);
DISPLAY INVISIBLE (2550 500);
FORCEADD Q_RES..1
(2725 575);
FORCEPROP 1 LAST PART_NUMBER CS00002JB13
J 0
(2675 625);
DISPLAY 0.404255 (2675 625);
DISPLAY INVISIBLE (2675 625);
FORCEPROP 1 LAST MATERIAL CHIP
J 0
(2975 575);
DISPLAY 0.510638 (2975 575);
FORCEPROP 1 LAST TOLERANCE 5%
J 0
(2900 575);
DISPLAY 0.510638 (2900 575);
FORCEPROP 1 LAST VALUE 0
J 2
(2875 575);
DISPLAY 0.510638 (2875 575);
FORCEPROP 1 LAST $LOCATION R1853
J 0
(2525 575);
DISPLAY 0.510638 (2525 575);
FORCEPROP 1 LASTPIN (2625 575) $PN 1
J 0
(2637 587);
DISPLAY 0.787234 (2637 587);
PAINT MONO (2637 587);
FORCEPROP 1 LASTPIN (2825 575) $PN 2
J 0
(2787 587);
DISPLAY 0.787234 (2787 587);
PAINT MONO (2787 587);
FORCEPROP 1 LAST PATH I138
J 0
(2675 725);
DISPLAY 0.978723 (2675 725);
PAINT WHITE (2675 725);
DISPLAY INVISIBLE (2675 725);
FORCEPROP 1 LAST WATTAGE 1/16W
J 2
(2900 650);
DISPLAY 0.404255 (2900 650);
DISPLAY INVISIBLE (2900 650);
FORCEPROP 1 LAST PACK_TYPE 0402LF
J 0
(2975 575);
DISPLAY 0.510638 (2975 575);
DISPLAY INVISIBLE (2975 575);
FORCEPROP 2 LAST CDS_LIB pure_quanta
J 0
(2725 575);
DISPLAY INVISIBLE (2725 575);
FORCEPROP 0 LAST CDS_LOCATION R1853
J 0
(2975 600);
DISPLAY 1.021277 (2975 600);
DISPLAY INVISIBLE (2975 600);
FORCEPROP 0 LAST $SEC 1
J 0
(2975 600);
DISPLAY 0.680851 (2975 600);
PAINT MONO (2975 600);
DISPLAY INVISIBLE (2975 600);
FORCEPROP 0 LAST CDS_SEC 1
J 0
(2975 600);
DISPLAY 1.021277 (2975 600);
DISPLAY INVISIBLE (2975 600);
FORCEADD Q_RES..1
(2725 700);
FORCEPROP 1 LAST PART_NUMBER CS00002JB13
J 0
(2675 750);
DISPLAY 0.404255 (2675 750);
DISPLAY INVISIBLE (2675 750);
FORCEPROP 1 LAST MATERIAL CHIP
J 0
(2975 700);
DISPLAY 0.510638 (2975 700);
FORCEPROP 1 LAST VALUE 0
J 2
(2875 700);
DISPLAY 0.510638 (2875 700);
FORCEPROP 1 LAST TOLERANCE 5%
J 0
(2900 700);
DISPLAY 0.510638 (2900 700);
FORCEPROP 1 LAST $LOCATION R1547
J 0
(2525 700);
DISPLAY 0.510638 (2525 700);
FORCEPROP 1 LASTPIN (2625 700) $PN 1
J 0
(2637 712);
DISPLAY 0.787234 (2637 712);
FORCEPROP 1 LASTPIN (2825 700) $PN 2
J 0
(2787 712);
DISPLAY 0.787234 (2787 712);
FORCEPROP 1 LAST PATH I139
J 0
(2675 850);
DISPLAY 0.978723 (2675 850);
PAINT WHITE (2675 850);
DISPLAY INVISIBLE (2675 850);
FORCEPROP 2 LAST CDS_LIB pure_quanta
J 0
(2725 700);
PAINT MONO (2725 700);
DISPLAY INVISIBLE (2725 700);
FORCEPROP 1 LAST WATTAGE 1/16W
J 2
(2900 775);
DISPLAY 0.404255 (2900 775);
DISPLAY INVISIBLE (2900 775);
FORCEPROP 1 LAST PACK_TYPE 0402LF
J 0
(2975 700);
DISPLAY 0.510638 (2975 700);
DISPLAY INVISIBLE (2975 700);
FORCEPROP 2 LAST CDS_LOCATION R1547
J 0
(2675 900);
DISPLAY 1.021277 (2675 900);
DISPLAY INVISIBLE (2675 900);
FORCEPROP 2 LAST $SEC 1
J 0
(2675 900);
DISPLAY 0.680851 (2675 900);
PAINT MONO (2675 900);
DISPLAY INVISIBLE (2675 900);
FORCEPROP 2 LAST CDS_SEC 1
J 0
(2675 900);
DISPLAY 1.021277 (2675 900);
DISPLAY INVISIBLE (2675 900);
FORCEADD Q_RES..1
(-2275 -1675);
FORCEPROP 1 LAST PART_NUMBER CS00002JB13
J 0
(-2325 -1625);
DISPLAY 0.404255 (-2325 -1625);
DISPLAY INVISIBLE (-2325 -1625);
FORCEPROP 1 LAST VALUE 0
J 2
(-2125 -1675);
DISPLAY 0.510638 (-2125 -1675);
FORCEPROP 1 LAST TOLERANCE 5%
J 0
(-2100 -1675);
DISPLAY 0.510638 (-2100 -1675);
FORCEPROP 1 LAST MATERIAL CHIP
J 0
(-2025 -1675);
DISPLAY 0.510638 (-2025 -1675);
FORCEPROP 1 LAST $LOCATION R4697
J 0
(-2475 -1675);
DISPLAY 0.638298 (-2475 -1675);
FORCEPROP 1 LASTPIN (-2375 -1675) $PN 1
J 0
(-2363 -1663);
DISPLAY 0.787234 (-2363 -1663);
PAINT MONO (-2363 -1663);
FORCEPROP 1 LASTPIN (-2175 -1675) $PN 2
J 0
(-2213 -1663);
DISPLAY 0.787234 (-2213 -1663);
PAINT MONO (-2213 -1663);
FORCEPROP 1 LAST PATH I14
J 0
(-2325 -1525);
DISPLAY 0.978723 (-2325 -1525);
PAINT WHITE (-2325 -1525);
DISPLAY INVISIBLE (-2325 -1525);
FORCEPROP 1 LAST WATTAGE 1/16W
J 2
(-2100 -1600);
DISPLAY 0.404255 (-2100 -1600);
DISPLAY INVISIBLE (-2100 -1600);
FORCEPROP 1 LAST PACK_TYPE 0402LF
J 0
(-2025 -1675);
DISPLAY 0.510638 (-2025 -1675);
DISPLAY INVISIBLE (-2025 -1675);
FORCEPROP 2 LAST CDS_LIB pure_quanta
J 0
(-2275 -1675);
DISPLAY INVISIBLE (-2275 -1675);
FORCEPROP 0 LAST CDS_LOCATION R4697
J 0
(-2475 -1625);
DISPLAY 1.021277 (-2475 -1625);
DISPLAY INVISIBLE (-2475 -1625);
FORCEPROP 0 LAST $SEC 1
J 0
(-2475 -1625);
DISPLAY 0.680851 (-2475 -1625);
PAINT MONO (-2475 -1625);
DISPLAY INVISIBLE (-2475 -1625);
FORCEPROP 0 LAST CDS_SEC 1
J 0
(-2475 -1625);
DISPLAY 1.021277 (-2475 -1625);
DISPLAY INVISIBLE (-2475 -1625);
FORCEADD Q_RES..1
(2725 950);
FORCEPROP 1 LAST PART_NUMBER CS11002FB07
J 0
(2550 1025);
DISPLAY 0.638298 (2550 1025);
DISPLAY INVISIBLE (2550 1025);
FORCEPROP 1 LAST VALUE 100
J 2
(2925 950);
DISPLAY 0.638298 (2925 950);
FORCEPROP 1 LAST WATTAGE 1/16W
J 2
(3000 900);
DISPLAY 0.638298 (3000 900);
FORCEPROP 1 LAST MATERIAL CHIP
J 0
(3025 950);
DISPLAY 0.638298 (3025 950);
FORCEPROP 1 LAST TOLERANCE 1%
J 0
(2950 950);
DISPLAY 0.638298 (2950 950);
FORCEPROP 1 LAST PACK_TYPE 0402LF
J 0
(2450 900);
DISPLAY 0.638298 (2450 900);
FORCEPROP 1 LAST $LOCATION R4625
J 0
(2525 950);
DISPLAY 0.638298 (2525 950);
FORCEPROP 1 LASTPIN (2625 950) $PN 1
J 0
(2637 962);
DISPLAY 0.787234 (2637 962);
PAINT MONO (2637 962);
FORCEPROP 1 LASTPIN (2825 950) $PN 2
J 0
(2787 962);
DISPLAY 0.787234 (2787 962);
PAINT MONO (2787 962);
FORCEPROP 1 LAST PATH I140
J 0
(2675 1100);
DISPLAY 0.978723 (2675 1100);
PAINT WHITE (2675 1100);
DISPLAY INVISIBLE (2675 1100);
FORCEPROP 2 LAST CDS_LIB pure_quanta
J 0
(2725 950);
DISPLAY INVISIBLE (2725 950);
FORCEPROP 0 LAST CDS_LOCATION R4625
J 0
(2550 1075);
DISPLAY 1.021277 (2550 1075);
DISPLAY INVISIBLE (2550 1075);
FORCEPROP 0 LAST $SEC 1
J 0
(2550 1075);
DISPLAY 0.680851 (2550 1075);
PAINT MONO (2550 1075);
DISPLAY INVISIBLE (2550 1075);
FORCEPROP 0 LAST CDS_SEC 1
J 0
(2550 1075);
DISPLAY 1.021277 (2550 1075);
DISPLAY INVISIBLE (2550 1075);
FORCEADD Q_RES..1
(2725 825);
FORCEPROP 1 LAST PART_NUMBER CS03322FB03
J 0
(2575 900);
DISPLAY 0.638298 (2575 900);
DISPLAY INVISIBLE (2575 900);
FORCEPROP 1 LAST MATERIAL CHIP
J 0
(3000 825);
DISPLAY 0.638298 (3000 825);
FORCEPROP 1 LAST VALUE 33.2
J 2
(2975 825);
DISPLAY 0.638298 (2975 825);
FORCEPROP 1 LAST $LOCATION R4495
J 0
(2475 825);
DISPLAY 0.638298 (2475 825);
FORCEPROP 1 LASTPIN (2625 825) $PN 1
J 0
(2637 837);
DISPLAY 0.787234 (2637 837);
PAINT MONO (2637 837);
FORCEPROP 1 LASTPIN (2825 825) $PN 2
J 0
(2787 837);
DISPLAY 0.787234 (2787 837);
PAINT MONO (2787 837);
FORCEPROP 1 LAST PATH I141
J 0
(2675 975);
DISPLAY 0.978723 (2675 975);
PAINT WHITE (2675 975);
DISPLAY INVISIBLE (2675 975);
FORCEPROP 2 LAST CDS_LIB pure_quanta
J 0
(2725 825);
DISPLAY INVISIBLE (2725 825);
FORCEPROP 1 LAST TOLERANCE 1%
J 0
(3000 825);
DISPLAY 0.638298 (3000 825);
DISPLAY INVISIBLE (3000 825);
FORCEPROP 1 LAST PACK_TYPE 0402LF
J 0
(2575 950);
DISPLAY 0.638298 (2575 950);
DISPLAY INVISIBLE (2575 950);
FORCEPROP 1 LAST WATTAGE 1/16W
J 2
(2925 950);
DISPLAY 0.638298 (2925 950);
DISPLAY INVISIBLE (2925 950);
FORCEPROP 0 LAST CDS_LOCATION R4495
J 0
(3000 875);
DISPLAY 1.021277 (3000 875);
DISPLAY INVISIBLE (3000 875);
FORCEPROP 0 LAST $SEC 1
J 0
(3000 875);
DISPLAY 0.680851 (3000 875);
PAINT MONO (3000 875);
DISPLAY INVISIBLE (3000 875);
FORCEPROP 0 LAST CDS_SEC 1
J 0
(3000 875);
DISPLAY 1.021277 (3000 875);
DISPLAY INVISIBLE (3000 875);
FORCEADD OFFPAGE..2
(2950 1975);
FORCEPROP 2 LAST $XR0 213 
J 0
(3139 1975);
DISPLAY 0.638298 (3139 1975);
PAINT MONO (3139 1975);
FORCEPROP 2 LAST PATH I142
J 0
(3150 2025);
DISPLAY 1.021277 (3150 2025);
DISPLAY INVISIBLE (3150 2025);
FORCEPROP 1 LAST COMMENT_BODY TRUE
J 0
(2905 1880);
DISPLAY 1.170213 (2905 1880);
PAINT GREEN (2905 1880);
DISPLAY INVISIBLE (2905 1880);
FORCEPROP 1 LAST OFFPAGE TRUE
J 0
(3275 1850);
DISPLAY 1.170213 (3275 1850);
PAINT GREEN (3275 1850);
DISPLAY INVISIBLE (3275 1850);
FORCEPROP 2 LAST CDS_LIB standard
J 0
(2950 1975);
DISPLAY INVISIBLE (2950 1975);
FORCEADD OFFPAGE..1
R 2
(2950 2025);
FORCEPROP 2 LAST $XR0 305 
J 0
(3136 2025);
DISPLAY 0.638298 (3136 2025);
PAINT MONO (3136 2025);
FORCEPROP 2 LAST PATH I143
J 0
(3150 2075);
DISPLAY 1.021277 (3150 2075);
DISPLAY INVISIBLE (3150 2075);
FORCEPROP 1 LAST COMMENT_BODY TRUE
J 2
(2825 1925);
DISPLAY 1.170213 (2825 1925);
PAINT GREEN (2825 1925);
DISPLAY INVISIBLE (2825 1925);
FORCEPROP 1 LAST OFFPAGE TRUE
J 2
(2625 1900);
DISPLAY 1.170213 (2625 1900);
PAINT GREEN (2625 1900);
DISPLAY INVISIBLE (2625 1900);
FORCEPROP 2 LAST CDS_LIB standard
J 0
(2950 2025);
DISPLAY INVISIBLE (2950 2025);
FORCEADD OFFPAGE..1
R 2
(2950 2075);
FORCEPROP 2 LAST $XR0 305 
J 0
(3136 2075);
DISPLAY 0.638298 (3136 2075);
PAINT MONO (3136 2075);
FORCEPROP 2 LAST PATH I144
J 0
(3150 2125);
DISPLAY 1.021277 (3150 2125);
DISPLAY INVISIBLE (3150 2125);
FORCEPROP 1 LAST OFFPAGE TRUE
J 2
(2625 1950);
DISPLAY 1.170213 (2625 1950);
PAINT GREEN (2625 1950);
DISPLAY INVISIBLE (2625 1950);
FORCEPROP 1 LAST COMMENT_BODY TRUE
J 2
(2825 1975);
DISPLAY 1.170213 (2825 1975);
PAINT GREEN (2825 1975);
DISPLAY INVISIBLE (2825 1975);
FORCEPROP 2 LAST CDS_LIB standard
J 0
(2950 2075);
DISPLAY INVISIBLE (2950 2075);
FORCEADD OFFPAGE..2
(2950 2225);
FORCEPROP 2 LAST $XR0 213 
J 0
(3139 2225);
DISPLAY 0.638298 (3139 2225);
PAINT MONO (3139 2225);
FORCEPROP 2 LAST PATH I145
J 0
(3150 2275);
DISPLAY 1.021277 (3150 2275);
DISPLAY INVISIBLE (3150 2275);
FORCEPROP 2 LAST CDS_LIB standard
J 0
(2950 2225);
DISPLAY INVISIBLE (2950 2225);
FORCEPROP 1 LAST OFFPAGE TRUE
J 0
(3275 2100);
DISPLAY 1.170213 (3275 2100);
PAINT GREEN (3275 2100);
DISPLAY INVISIBLE (3275 2100);
FORCEPROP 1 LAST COMMENT_BODY TRUE
J 0
(2905 2130);
DISPLAY 1.170213 (2905 2130);
PAINT GREEN (2905 2130);
DISPLAY INVISIBLE (2905 2130);
FORCEADD OFFPAGE..1
R 2
(2950 2275);
FORCEPROP 2 LAST $XR0 220 
J 0
(3136 2275);
DISPLAY 0.638298 (3136 2275);
PAINT MONO (3136 2275);
FORCEPROP 2 LAST PATH I146
J 0
(3150 2325);
DISPLAY 1.021277 (3150 2325);
DISPLAY INVISIBLE (3150 2325);
FORCEPROP 2 LAST CDS_LIB standard
J 0
(2950 2275);
PAINT MONO (2950 2275);
DISPLAY INVISIBLE (2950 2275);
FORCEPROP 1 LAST OFFPAGE TRUE
J 2
(2625 2150);
DISPLAY 1.170213 (2625 2150);
PAINT GREEN (2625 2150);
DISPLAY INVISIBLE (2625 2150);
FORCEPROP 1 LAST COMMENT_BODY TRUE
J 2
(2825 2175);
DISPLAY 1.170213 (2825 2175);
PAINT GREEN (2825 2175);
DISPLAY INVISIBLE (2825 2175);
FORCEADD OFFPAGE..2
(2950 2375);
FORCEPROP 2 LAST $XR0 159 
J 0
(3139 2375);
DISPLAY 0.638298 (3139 2375);
PAINT MONO (3139 2375);
FORCEPROP 2 LAST PATH I147
J 0
(3150 2425);
DISPLAY 1.021277 (3150 2425);
DISPLAY INVISIBLE (3150 2425);
FORCEPROP 2 LAST CDS_LIB standard
J 0
(2950 2375);
DISPLAY INVISIBLE (2950 2375);
FORCEPROP 1 LAST COMMENT_BODY TRUE
J 0
(2905 2280);
DISPLAY 1.170213 (2905 2280);
PAINT GREEN (2905 2280);
DISPLAY INVISIBLE (2905 2280);
FORCEPROP 1 LAST OFFPAGE TRUE
J 0
(3275 2250);
DISPLAY 1.170213 (3275 2250);
PAINT GREEN (3275 2250);
DISPLAY INVISIBLE (3275 2250);
FORCEADD OFFPAGE..1
R 2
(2950 2325);
FORCEPROP 2 LAST $XR0 213 
J 0
(3136 2325);
DISPLAY 0.638298 (3136 2325);
PAINT MONO (3136 2325);
FORCEPROP 2 LAST PATH I148
J 0
(3150 2375);
DISPLAY 1.021277 (3150 2375);
DISPLAY INVISIBLE (3150 2375);
FORCEPROP 2 LAST CDS_LIB standard
J 0
(2950 2325);
PAINT MONO (2950 2325);
DISPLAY INVISIBLE (2950 2325);
FORCEPROP 1 LAST COMMENT_BODY TRUE
J 2
(2825 2225);
DISPLAY 1.170213 (2825 2225);
PAINT GREEN (2825 2225);
DISPLAY INVISIBLE (2825 2225);
FORCEPROP 1 LAST OFFPAGE TRUE
J 2
(2625 2200);
DISPLAY 1.170213 (2625 2200);
PAINT GREEN (2625 2200);
DISPLAY INVISIBLE (2625 2200);
FORCEADD OFFPAGE..2
(2950 2475);
FORCEPROP 2 LAST $XR0 159 
J 0
(3139 2475);
DISPLAY 0.638298 (3139 2475);
PAINT MONO (3139 2475);
FORCEPROP 2 LAST PATH I149
J 0
(3150 2525);
DISPLAY 1.021277 (3150 2525);
DISPLAY INVISIBLE (3150 2525);
FORCEPROP 1 LAST COMMENT_BODY TRUE
J 0
(2905 2380);
DISPLAY 1.170213 (2905 2380);
PAINT GREEN (2905 2380);
DISPLAY INVISIBLE (2905 2380);
FORCEPROP 1 LAST OFFPAGE TRUE
J 0
(3275 2350);
DISPLAY 1.170213 (3275 2350);
PAINT GREEN (3275 2350);
DISPLAY INVISIBLE (3275 2350);
FORCEPROP 2 LAST CDS_LIB standard
J 0
(2950 2475);
DISPLAY INVISIBLE (2950 2475);
FORCEADD Q_RES..1
(-2225 -1375);
FORCEPROP 1 LAST PART_NUMBER CS03322FB03
J 0
(-2375 -1300);
DISPLAY 0.638298 (-2375 -1300);
DISPLAY INVISIBLE (-2375 -1300);
FORCEPROP 1 LAST VALUE 33.2
J 2
(-1975 -1375);
DISPLAY 0.638298 (-1975 -1375);
FORCEPROP 1 LAST MATERIAL CHIP
J 0
(-1950 -1375);
DISPLAY 0.638298 (-1950 -1375);
FORCEPROP 1 LAST LOCATION R3486
J 0
(-2475 -1375);
DISPLAY 0.638298 (-2475 -1375);
FORCEPROP 1 LASTPIN (-2325 -1375) $PN 1
J 0
(-2313 -1363);
DISPLAY 0.787234 (-2313 -1363);
PAINT MONO (-2313 -1363);
FORCEPROP 1 LASTPIN (-2125 -1375) $PN 2
J 0
(-2163 -1363);
DISPLAY 0.787234 (-2163 -1363);
PAINT MONO (-2163 -1363);
FORCEPROP 1 LAST PATH I15
J 0
(-2275 -1225);
DISPLAY 0.978723 (-2275 -1225);
PAINT WHITE (-2275 -1225);
DISPLAY INVISIBLE (-2275 -1225);
FORCEPROP 1 LAST TOLERANCE 1%
J 0
(-1950 -1375);
DISPLAY 0.638298 (-1950 -1375);
DISPLAY INVISIBLE (-1950 -1375);
FORCEPROP 1 LAST PACK_TYPE 0402LF
J 0
(-2375 -1250);
DISPLAY 0.638298 (-2375 -1250);
DISPLAY INVISIBLE (-2375 -1250);
FORCEPROP 1 LAST WATTAGE 1/16W
J 2
(-2025 -1250);
DISPLAY 0.638298 (-2025 -1250);
DISPLAY INVISIBLE (-2025 -1250);
FORCEPROP 2 LAST CDS_LIB pure_quanta
J 0
(-2225 -1375);
DISPLAY INVISIBLE (-2225 -1375);
FORCEPROP 0 LAST $SEC 1
J 0
(-1950 -1325);
DISPLAY 0.680851 (-1950 -1325);
PAINT MONO (-1950 -1325);
DISPLAY INVISIBLE (-1950 -1325);
FORCEPROP 0 LAST CDS_SEC 1
J 0
(-1950 -1325);
DISPLAY 1.021277 (-1950 -1325);
DISPLAY INVISIBLE (-1950 -1325);
FORCEADD OFFPAGE..1
R 2
(2950 2425);
FORCEPROP 2 LAST $XR0 159 
J 0
(3136 2425);
DISPLAY 0.638298 (3136 2425);
PAINT MONO (3136 2425);
FORCEPROP 2 LAST PATH I150
J 0
(3150 2475);
DISPLAY 1.021277 (3150 2475);
DISPLAY INVISIBLE (3150 2475);
FORCEPROP 1 LAST OFFPAGE TRUE
J 2
(2625 2300);
DISPLAY 1.170213 (2625 2300);
PAINT GREEN (2625 2300);
DISPLAY INVISIBLE (2625 2300);
FORCEPROP 1 LAST COMMENT_BODY TRUE
J 2
(2825 2325);
DISPLAY 1.170213 (2825 2325);
PAINT GREEN (2825 2325);
DISPLAY INVISIBLE (2825 2325);
FORCEPROP 2 LAST CDS_LIB standard
J 0
(2950 2425);
DISPLAY INVISIBLE (2950 2425);
FORCEADD OFFPAGE..2
(2950 2525);
FORCEPROP 2 LAST $XR0 159 
J 0
(3139 2525);
DISPLAY 0.638298 (3139 2525);
PAINT MONO (3139 2525);
FORCEPROP 2 LAST PATH I151
J 0
(3150 2575);
DISPLAY 1.021277 (3150 2575);
DISPLAY INVISIBLE (3150 2575);
FORCEPROP 2 LAST CDS_LIB standard
J 0
(2950 2525);
DISPLAY INVISIBLE (2950 2525);
FORCEPROP 1 LAST COMMENT_BODY TRUE
J 0
(2905 2430);
DISPLAY 1.170213 (2905 2430);
PAINT GREEN (2905 2430);
DISPLAY INVISIBLE (2905 2430);
FORCEPROP 1 LAST OFFPAGE TRUE
J 0
(3275 2400);
DISPLAY 1.170213 (3275 2400);
PAINT GREEN (3275 2400);
DISPLAY INVISIBLE (3275 2400);
FORCEADD OFFPAGE..1
R 2
(2950 2625);
FORCEPROP 2 LAST $XR0 153 
J 0
(3136 2625);
DISPLAY 0.638298 (3136 2625);
PAINT MONO (3136 2625);
FORCEPROP 2 LAST PATH I152
J 0
(3150 2675);
DISPLAY 1.021277 (3150 2675);
DISPLAY INVISIBLE (3150 2675);
FORCEPROP 2 LAST CDS_LIB standard
J 0
(2950 2625);
DISPLAY INVISIBLE (2950 2625);
FORCEPROP 1 LAST COMMENT_BODY TRUE
J 2
(2825 2525);
DISPLAY 1.170213 (2825 2525);
PAINT GREEN (2825 2525);
DISPLAY INVISIBLE (2825 2525);
FORCEPROP 1 LAST OFFPAGE TRUE
J 2
(2625 2500);
DISPLAY 1.170213 (2625 2500);
PAINT GREEN (2625 2500);
DISPLAY INVISIBLE (2625 2500);
FORCEADD OFFPAGE..2
(2950 2575);
FORCEPROP 2 LAST $XR0 153 
J 0
(3139 2575);
DISPLAY 0.638298 (3139 2575);
PAINT MONO (3139 2575);
FORCEPROP 2 LAST PATH I153
J 0
(3150 2625);
DISPLAY 1.021277 (3150 2625);
DISPLAY INVISIBLE (3150 2625);
FORCEPROP 1 LAST COMMENT_BODY TRUE
J 0
(2905 2480);
DISPLAY 1.170213 (2905 2480);
PAINT GREEN (2905 2480);
DISPLAY INVISIBLE (2905 2480);
FORCEPROP 1 LAST OFFPAGE TRUE
J 0
(3275 2450);
DISPLAY 1.170213 (3275 2450);
PAINT GREEN (3275 2450);
DISPLAY INVISIBLE (3275 2450);
FORCEPROP 2 LAST CDS_LIB standard
J 0
(2950 2575);
DISPLAY INVISIBLE (2950 2575);
FORCEADD OFFPAGE..2
(2950 2725);
FORCEPROP 2 LAST $XR0 153 
J 0
(3139 2725);
DISPLAY 0.638298 (3139 2725);
PAINT MONO (3139 2725);
FORCEPROP 2 LAST PATH I154
J 0
(3150 2775);
DISPLAY 1.021277 (3150 2775);
DISPLAY INVISIBLE (3150 2775);
FORCEPROP 1 LAST OFFPAGE TRUE
J 0
(3275 2600);
DISPLAY 1.170213 (3275 2600);
PAINT GREEN (3275 2600);
DISPLAY INVISIBLE (3275 2600);
FORCEPROP 1 LAST COMMENT_BODY TRUE
J 0
(2905 2630);
DISPLAY 1.170213 (2905 2630);
PAINT GREEN (2905 2630);
DISPLAY INVISIBLE (2905 2630);
FORCEPROP 2 LAST CDS_LIB standard
J 0
(2950 2725);
DISPLAY INVISIBLE (2950 2725);
FORCEADD OFFPAGE..2
(2950 2675);
FORCEPROP 2 LAST $XR0 153 
J 0
(3139 2675);
DISPLAY 0.638298 (3139 2675);
PAINT MONO (3139 2675);
FORCEPROP 2 LAST PATH I155
J 0
(3150 2725);
DISPLAY 1.021277 (3150 2725);
DISPLAY INVISIBLE (3150 2725);
FORCEPROP 2 LAST CDS_LIB standard
J 0
(2950 2675);
DISPLAY INVISIBLE (2950 2675);
FORCEPROP 1 LAST OFFPAGE TRUE
J 0
(3275 2550);
DISPLAY 1.170213 (3275 2550);
PAINT GREEN (3275 2550);
DISPLAY INVISIBLE (3275 2550);
FORCEPROP 1 LAST COMMENT_BODY TRUE
J 0
(2905 2580);
DISPLAY 1.170213 (2905 2580);
PAINT GREEN (2905 2580);
DISPLAY INVISIBLE (2905 2580);
FORCEADD OFFPAGE..2
(2950 2775);
FORCEPROP 2 LAST $XR0 222 
J 0
(3139 2775);
DISPLAY 0.638298 (3139 2775);
PAINT MONO (3139 2775);
FORCEPROP 2 LAST PATH I156
J 0
(3150 2825);
DISPLAY 1.021277 (3150 2825);
DISPLAY INVISIBLE (3150 2825);
FORCEPROP 1 LAST COMMENT_BODY TRUE
J 0
(2905 2680);
DISPLAY 1.170213 (2905 2680);
PAINT GREEN (2905 2680);
DISPLAY INVISIBLE (2905 2680);
FORCEPROP 1 LAST OFFPAGE TRUE
J 0
(3275 2650);
DISPLAY 1.170213 (3275 2650);
PAINT GREEN (3275 2650);
DISPLAY INVISIBLE (3275 2650);
FORCEPROP 2 LAST CDS_LIB standard
J 0
(2950 2775);
DISPLAY INVISIBLE (2950 2775);
FORCEADD OFFPAGE..2
(2950 2875);
FORCEPROP 2 LAST $XR0 222 
J 0
(3139 2875);
DISPLAY 0.638298 (3139 2875);
PAINT MONO (3139 2875);
FORCEPROP 2 LAST PATH I157
J 0
(3150 2925);
DISPLAY 1.021277 (3150 2925);
DISPLAY INVISIBLE (3150 2925);
FORCEPROP 2 LAST CDS_LIB standard
J 0
(2950 2875);
DISPLAY INVISIBLE (2950 2875);
FORCEPROP 1 LAST OFFPAGE TRUE
J 0
(3275 2750);
DISPLAY 1.170213 (3275 2750);
PAINT GREEN (3275 2750);
DISPLAY INVISIBLE (3275 2750);
FORCEPROP 1 LAST COMMENT_BODY TRUE
J 0
(2905 2780);
DISPLAY 1.170213 (2905 2780);
PAINT GREEN (2905 2780);
DISPLAY INVISIBLE (2905 2780);
FORCEADD OFFPAGE..1
R 2
(2950 2825);
FORCEPROP 2 LAST $XR0 222 
J 0
(3136 2825);
DISPLAY 0.638298 (3136 2825);
PAINT MONO (3136 2825);
FORCEPROP 2 LAST PATH I158
J 0
(3150 2875);
DISPLAY 1.021277 (3150 2875);
DISPLAY INVISIBLE (3150 2875);
FORCEPROP 2 LAST CDS_LIB standard
J 0
(2950 2825);
DISPLAY INVISIBLE (2950 2825);
FORCEPROP 1 LAST COMMENT_BODY TRUE
J 2
(2825 2725);
DISPLAY 1.170213 (2825 2725);
PAINT GREEN (2825 2725);
DISPLAY INVISIBLE (2825 2725);
FORCEPROP 1 LAST OFFPAGE TRUE
J 2
(2625 2700);
DISPLAY 1.170213 (2625 2700);
PAINT GREEN (2625 2700);
DISPLAY INVISIBLE (2625 2700);
FORCEADD OFFPAGE..2
(2950 2925);
FORCEPROP 2 LAST $XR0 222 
J 0
(3139 2925);
DISPLAY 0.638298 (3139 2925);
PAINT MONO (3139 2925);
FORCEPROP 2 LAST PATH I159
J 0
(3150 2975);
DISPLAY 1.021277 (3150 2975);
DISPLAY INVISIBLE (3150 2975);
FORCEPROP 1 LAST OFFPAGE TRUE
J 0
(3275 2800);
DISPLAY 1.170213 (3275 2800);
PAINT GREEN (3275 2800);
DISPLAY INVISIBLE (3275 2800);
FORCEPROP 1 LAST COMMENT_BODY TRUE
J 0
(2905 2830);
DISPLAY 1.170213 (2905 2830);
PAINT GREEN (2905 2830);
DISPLAY INVISIBLE (2905 2830);
FORCEPROP 2 LAST CDS_LIB standard
J 0
(2950 2925);
DISPLAY INVISIBLE (2950 2925);
FORCEADD Q_RES..1
(-2225 -1500);
FORCEPROP 1 LAST PART_NUMBER CS03322FB03
J 0
(-2375 -1425);
DISPLAY 0.638298 (-2375 -1425);
DISPLAY INVISIBLE (-2375 -1425);
FORCEPROP 1 LAST MATERIAL CHIP
J 0
(-1950 -1500);
DISPLAY 0.638298 (-1950 -1500);
FORCEPROP 1 LAST VALUE 33.2
J 2
(-1975 -1500);
DISPLAY 0.638298 (-1975 -1500);
FORCEPROP 1 LAST LOCATION R3505
J 0
(-2475 -1500);
DISPLAY 0.638298 (-2475 -1500);
FORCEPROP 1 LASTPIN (-2325 -1500) $PN 1
J 0
(-2313 -1488);
DISPLAY 0.787234 (-2313 -1488);
PAINT MONO (-2313 -1488);
FORCEPROP 1 LASTPIN (-2125 -1500) $PN 2
J 0
(-2163 -1488);
DISPLAY 0.787234 (-2163 -1488);
PAINT MONO (-2163 -1488);
FORCEPROP 1 LAST PATH I16
J 0
(-2275 -1350);
DISPLAY 0.978723 (-2275 -1350);
PAINT WHITE (-2275 -1350);
DISPLAY INVISIBLE (-2275 -1350);
FORCEPROP 1 LAST TOLERANCE 1%
J 0
(-1950 -1500);
DISPLAY 0.638298 (-1950 -1500);
DISPLAY INVISIBLE (-1950 -1500);
FORCEPROP 1 LAST PACK_TYPE 0402LF
J 0
(-2375 -1375);
DISPLAY 0.638298 (-2375 -1375);
DISPLAY INVISIBLE (-2375 -1375);
FORCEPROP 1 LAST WATTAGE 1/16W
J 2
(-2025 -1375);
DISPLAY 0.638298 (-2025 -1375);
DISPLAY INVISIBLE (-2025 -1375);
FORCEPROP 2 LAST CDS_LIB pure_quanta
J 0
(-2225 -1500);
DISPLAY INVISIBLE (-2225 -1500);
FORCEPROP 0 LAST $SEC 1
J 0
(-1950 -1450);
DISPLAY 0.680851 (-1950 -1450);
PAINT MONO (-1950 -1450);
DISPLAY INVISIBLE (-1950 -1450);
FORCEPROP 0 LAST CDS_SEC 1
J 0
(-1950 -1450);
DISPLAY 1.021277 (-1950 -1450);
DISPLAY INVISIBLE (-1950 -1450);
FORCEADD OFFPAGE..1
R 2
(2950 3025);
FORCEPROP 2 LAST $XR0 222 
J 0
(3136 3025);
DISPLAY 0.638298 (3136 3025);
PAINT MONO (3136 3025);
FORCEPROP 2 LAST PATH I160
J 0
(3150 3075);
DISPLAY 1.021277 (3150 3075);
DISPLAY INVISIBLE (3150 3075);
FORCEPROP 1 LAST OFFPAGE TRUE
J 2
(2625 2900);
DISPLAY 0.872340 (2625 2900);
DISPLAY INVISIBLE (2625 2900);
FORCEPROP 1 LAST COMMENT_BODY TRUE
J 2
(2825 2925);
DISPLAY 1.170213 (2825 2925);
PAINT GREEN (2825 2925);
DISPLAY INVISIBLE (2825 2925);
FORCEPROP 2 LAST CDS_LIB standard
J 2
(2950 3025);
PAINT MONO (2950 3025);
DISPLAY INVISIBLE (2950 3025);
FORCEADD OFFPAGE..1
R 2
(2950 3125);
FORCEPROP 2 LAST $XR0 222 
J 0
(3136 3125);
DISPLAY 0.638298 (3136 3125);
PAINT MONO (3136 3125);
FORCEPROP 2 LAST PATH I161
J 0
(3150 3175);
DISPLAY 1.021277 (3150 3175);
DISPLAY INVISIBLE (3150 3175);
FORCEPROP 2 LAST CDS_LIB standard
J 2
(2950 3125);
PAINT MONO (2950 3125);
DISPLAY INVISIBLE (2950 3125);
FORCEPROP 1 LAST COMMENT_BODY TRUE
J 2
(2825 3025);
DISPLAY 1.170213 (2825 3025);
PAINT GREEN (2825 3025);
DISPLAY INVISIBLE (2825 3025);
FORCEPROP 1 LAST OFFPAGE TRUE
J 2
(2625 3000);
DISPLAY 0.872340 (2625 3000);
DISPLAY INVISIBLE (2625 3000);
FORCEADD OFFPAGE..5
R 2
(2950 3075);
FORCEPROP 2 LAST $XR0 222 
J 0
(3139 3075);
DISPLAY 0.638298 (3139 3075);
PAINT MONO (3139 3075);
FORCEPROP 2 LAST PATH I162
J 0
(3150 3125);
DISPLAY 1.021277 (3150 3125);
DISPLAY INVISIBLE (3150 3125);
FORCEPROP 1 LAST OFFPAGE TRUE
J 2
(2625 2950);
DISPLAY 0.872340 (2625 2950);
DISPLAY INVISIBLE (2625 2950);
FORCEPROP 1 LAST COMMENT_BODY TRUE
J 2
(2850 3000);
DISPLAY 1.170213 (2850 3000);
PAINT GREEN (2850 3000);
DISPLAY INVISIBLE (2850 3000);
FORCEPROP 2 LAST CDS_LIB standard
J 2
(2950 3075);
DISPLAY INVISIBLE (2950 3075);
FORCEADD OFFPAGE..1
R 2
(2950 3275);
FORCEPROP 2 LAST $XR1 254 
J 0
(3256 3275);
DISPLAY 0.638298 (3256 3275);
PAINT MONO (3256 3275);
FORCEPROP 2 LAST $XR0 299 
J 0
(3136 3275);
DISPLAY 0.638298 (3136 3275);
PAINT MONO (3136 3275);
FORCEPROP 2 LAST PATH I163
J 0
(3275 3325);
DISPLAY 1.021277 (3275 3325);
DISPLAY INVISIBLE (3275 3325);
FORCEPROP 1 LAST COMMENT_BODY TRUE
J 2
(2825 3175);
DISPLAY 1.170213 (2825 3175);
PAINT GREEN (2825 3175);
DISPLAY INVISIBLE (2825 3175);
FORCEPROP 1 LAST OFFPAGE TRUE
J 2
(2625 3150);
DISPLAY 1.170213 (2625 3150);
PAINT GREEN (2625 3150);
DISPLAY INVISIBLE (2625 3150);
FORCEPROP 2 LAST CDS_LIB standard
J 0
(2950 3275);
DISPLAY INVISIBLE (2950 3275);
FORCEADD OFFPAGE..2
(2950 3225);
FORCEPROP 2 LAST $XR0 160 
J 0
(3139 3225);
DISPLAY 0.638298 (3139 3225);
PAINT MONO (3139 3225);
FORCEPROP 2 LAST PATH I164
J 0
(3150 3275);
DISPLAY 1.021277 (3150 3275);
DISPLAY INVISIBLE (3150 3275);
FORCEPROP 2 LAST CDS_LIB standard
J 0
(2950 3225);
DISPLAY INVISIBLE (2950 3225);
FORCEPROP 1 LAST COMMENT_BODY TRUE
J 0
(2905 3130);
DISPLAY 1.170213 (2905 3130);
PAINT GREEN (2905 3130);
DISPLAY INVISIBLE (2905 3130);
FORCEPROP 1 LAST OFFPAGE TRUE
J 0
(3275 3100);
DISPLAY 1.170213 (3275 3100);
PAINT GREEN (3275 3100);
DISPLAY INVISIBLE (3275 3100);
FORCEADD OFFPAGE..1
R 2
(2950 3175);
FORCEPROP 2 LAST $XR0 222 
J 0
(3136 3175);
DISPLAY 0.638298 (3136 3175);
PAINT MONO (3136 3175);
FORCEPROP 2 LAST PATH I165
J 0
(3150 3225);
DISPLAY 1.021277 (3150 3225);
DISPLAY INVISIBLE (3150 3225);
FORCEPROP 1 LAST COMMENT_BODY TRUE
J 2
(2825 3075);
DISPLAY 1.170213 (2825 3075);
PAINT GREEN (2825 3075);
DISPLAY INVISIBLE (2825 3075);
FORCEPROP 1 LAST OFFPAGE TRUE
J 2
(2625 3050);
DISPLAY 0.872340 (2625 3050);
DISPLAY INVISIBLE (2625 3050);
FORCEPROP 2 LAST CDS_LIB standard
J 2
(2950 3175);
PAINT MONO (2950 3175);
DISPLAY INVISIBLE (2950 3175);
FORCEADD OFFPAGE..1
R 2
(2950 3375);
FORCEPROP 2 LAST $XR1 254 
J 0
(3256 3375);
DISPLAY 0.638298 (3256 3375);
PAINT MONO (3256 3375);
FORCEPROP 2 LAST $XR0 300 
J 0
(3136 3375);
DISPLAY 0.638298 (3136 3375);
PAINT MONO (3136 3375);
FORCEPROP 2 LAST PATH I166
J 0
(3275 3425);
DISPLAY 1.021277 (3275 3425);
DISPLAY INVISIBLE (3275 3425);
FORCEPROP 2 LAST CDS_LIB standard
J 0
(2950 3375);
DISPLAY INVISIBLE (2950 3375);
FORCEPROP 1 LAST OFFPAGE TRUE
J 2
(2625 3250);
DISPLAY 1.170213 (2625 3250);
PAINT GREEN (2625 3250);
DISPLAY INVISIBLE (2625 3250);
FORCEPROP 1 LAST COMMENT_BODY TRUE
J 2
(2825 3275);
DISPLAY 1.170213 (2825 3275);
PAINT GREEN (2825 3275);
DISPLAY INVISIBLE (2825 3275);
FORCEADD OFFPAGE..1
R 2
(2950 3325);
FORCEPROP 2 LAST $XR1 253 
J 0
(3256 3325);
DISPLAY 0.638298 (3256 3325);
PAINT MONO (3256 3325);
FORCEPROP 2 LAST $XR0 281 
J 0
(3136 3325);
DISPLAY 0.638298 (3136 3325);
PAINT MONO (3136 3325);
FORCEPROP 2 LAST PATH I167
J 0
(3275 3375);
DISPLAY 1.021277 (3275 3375);
DISPLAY INVISIBLE (3275 3375);
FORCEPROP 2 LAST CDS_LIB standard
J 0
(2950 3325);
DISPLAY INVISIBLE (2950 3325);
FORCEPROP 1 LAST OFFPAGE TRUE
J 2
(2625 3200);
DISPLAY 1.170213 (2625 3200);
PAINT GREEN (2625 3200);
DISPLAY INVISIBLE (2625 3200);
FORCEPROP 1 LAST COMMENT_BODY TRUE
J 2
(2825 3225);
DISPLAY 1.170213 (2825 3225);
PAINT GREEN (2825 3225);
DISPLAY INVISIBLE (2825 3225);
FORCEADD OFFPAGE..1
R 2
(2950 3525);
FORCEPROP 2 LAST $XR1 253 
J 0
(3256 3525);
DISPLAY 0.638298 (3256 3525);
PAINT MONO (3256 3525);
FORCEPROP 2 LAST $XR0 266 
J 0
(3136 3525);
DISPLAY 0.638298 (3136 3525);
PAINT MONO (3136 3525);
FORCEPROP 2 LAST PATH I168
J 0
(3275 3575);
DISPLAY 1.021277 (3275 3575);
DISPLAY INVISIBLE (3275 3575);
FORCEPROP 2 LAST CDS_LIB standard
J 0
(2950 3525);
DISPLAY INVISIBLE (2950 3525);
FORCEPROP 1 LAST OFFPAGE TRUE
J 2
(2625 3400);
DISPLAY 1.170213 (2625 3400);
PAINT GREEN (2625 3400);
DISPLAY INVISIBLE (2625 3400);
FORCEPROP 1 LAST COMMENT_BODY TRUE
J 2
(2825 3425);
DISPLAY 1.170213 (2825 3425);
PAINT GREEN (2825 3425);
DISPLAY INVISIBLE (2825 3425);
FORCEADD OFFPAGE..2
(2950 3475);
FORCEPROP 2 LAST $XR2 253 
J 0
(3379 3475);
DISPLAY 0.638298 (3379 3475);
PAINT MONO (3379 3475);
FORCEPROP 2 LAST $XR1 132 
J 0
(3259 3475);
DISPLAY 0.638298 (3259 3475);
PAINT MONO (3259 3475);
FORCEPROP 2 LAST $XR0 282 
J 0
(3139 3475);
DISPLAY 0.638298 (3139 3475);
PAINT MONO (3139 3475);
FORCEPROP 2 LAST PATH I169
J 0
(3400 3525);
DISPLAY 1.021277 (3400 3525);
DISPLAY INVISIBLE (3400 3525);
FORCEPROP 2 LAST CDS_LIB standard
J 0
(2950 3475);
DISPLAY INVISIBLE (2950 3475);
FORCEPROP 1 LAST COMMENT_BODY TRUE
J 0
(2905 3380);
DISPLAY 1.170213 (2905 3380);
PAINT GREEN (2905 3380);
DISPLAY INVISIBLE (2905 3380);
FORCEPROP 1 LAST OFFPAGE TRUE
J 0
(3275 3350);
DISPLAY 1.170213 (3275 3350);
PAINT GREEN (3275 3350);
DISPLAY INVISIBLE (3275 3350);
FORCEADD Q_RES..1
(-2225 -1125);
FORCEPROP 1 LAST PART_NUMBER CS03322FB03
J 0
(-2375 -1050);
DISPLAY 0.638298 (-2375 -1050);
DISPLAY INVISIBLE (-2375 -1050);
FORCEPROP 1 LAST VALUE 33.2
J 2
(-1975 -1125);
DISPLAY 0.638298 (-1975 -1125);
FORCEPROP 1 LAST MATERIAL CHIP
J 0
(-1950 -1125);
DISPLAY 0.638298 (-1950 -1125);
FORCEPROP 1 LAST LOCATION R3484
J 0
(-2475 -1125);
DISPLAY 0.638298 (-2475 -1125);
FORCEPROP 1 LASTPIN (-2325 -1125) $PN 1
J 0
(-2313 -1113);
DISPLAY 0.787234 (-2313 -1113);
PAINT MONO (-2313 -1113);
FORCEPROP 1 LASTPIN (-2125 -1125) $PN 2
J 0
(-2163 -1113);
DISPLAY 0.787234 (-2163 -1113);
PAINT MONO (-2163 -1113);
FORCEPROP 1 LAST PATH I17
J 0
(-2275 -975);
DISPLAY 0.978723 (-2275 -975);
PAINT WHITE (-2275 -975);
DISPLAY INVISIBLE (-2275 -975);
FORCEPROP 2 LAST CDS_LIB pure_quanta
J 0
(-2225 -1125);
DISPLAY INVISIBLE (-2225 -1125);
FORCEPROP 1 LAST WATTAGE 1/16W
J 2
(-2025 -1000);
DISPLAY 0.638298 (-2025 -1000);
DISPLAY INVISIBLE (-2025 -1000);
FORCEPROP 1 LAST PACK_TYPE 0402LF
J 0
(-2375 -1000);
DISPLAY 0.638298 (-2375 -1000);
DISPLAY INVISIBLE (-2375 -1000);
FORCEPROP 1 LAST TOLERANCE 1%
J 0
(-1950 -1125);
DISPLAY 0.638298 (-1950 -1125);
DISPLAY INVISIBLE (-1950 -1125);
FORCEPROP 0 LAST $SEC 1
J 0
(-1950 -1075);
DISPLAY 0.680851 (-1950 -1075);
PAINT MONO (-1950 -1075);
DISPLAY INVISIBLE (-1950 -1075);
FORCEPROP 0 LAST CDS_SEC 1
J 0
(-1950 -1075);
DISPLAY 1.021277 (-1950 -1075);
DISPLAY INVISIBLE (-1950 -1075);
FORCEADD OFFPAGE..1
R 2
(2950 3425);
FORCEPROP 2 LAST $XR0 262 
J 0
(3136 3425);
DISPLAY 0.638298 (3136 3425);
PAINT MONO (3136 3425);
FORCEPROP 2 LAST PATH I170
J 0
(3150 3475);
DISPLAY 1.021277 (3150 3475);
DISPLAY INVISIBLE (3150 3475);
FORCEPROP 2 LAST CDS_LIB standard
J 0
(2950 3425);
DISPLAY INVISIBLE (2950 3425);
FORCEPROP 1 LAST OFFPAGE TRUE
J 2
(2625 3300);
DISPLAY 1.170213 (2625 3300);
PAINT GREEN (2625 3300);
DISPLAY INVISIBLE (2625 3300);
FORCEPROP 1 LAST COMMENT_BODY TRUE
J 2
(2825 3325);
DISPLAY 1.170213 (2825 3325);
PAINT GREEN (2825 3325);
DISPLAY INVISIBLE (2825 3325);
FORCEADD OFFPAGE..1
R 2
(2950 3575);
FORCEPROP 2 LAST $XR1 253 
J 0
(3256 3575);
DISPLAY 0.638298 (3256 3575);
PAINT MONO (3256 3575);
FORCEPROP 2 LAST $XR0 266 
J 0
(3136 3575);
DISPLAY 0.638298 (3136 3575);
PAINT MONO (3136 3575);
FORCEPROP 2 LAST PATH I171
J 0
(3275 3625);
DISPLAY 1.021277 (3275 3625);
DISPLAY INVISIBLE (3275 3625);
FORCEPROP 2 LAST CDS_LIB standard
J 0
(2950 3575);
DISPLAY INVISIBLE (2950 3575);
FORCEPROP 1 LAST OFFPAGE TRUE
J 2
(2625 3450);
DISPLAY 1.170213 (2625 3450);
PAINT GREEN (2625 3450);
DISPLAY INVISIBLE (2625 3450);
FORCEPROP 1 LAST COMMENT_BODY TRUE
J 2
(2825 3475);
DISPLAY 1.170213 (2825 3475);
PAINT GREEN (2825 3475);
DISPLAY INVISIBLE (2825 3475);
FORCEADD OFFPAGE..1
R 2
(2950 3625);
FORCEPROP 2 LAST $XR1 253 
J 0
(3256 3625);
DISPLAY 0.638298 (3256 3625);
PAINT MONO (3256 3625);
FORCEPROP 2 LAST $XR0 278 
J 0
(3136 3625);
DISPLAY 0.638298 (3136 3625);
PAINT MONO (3136 3625);
FORCEPROP 2 LAST PATH I172
J 0
(3275 3675);
DISPLAY 1.021277 (3275 3675);
DISPLAY INVISIBLE (3275 3675);
FORCEPROP 2 LAST CDS_LIB standard
J 0
(2950 3625);
DISPLAY INVISIBLE (2950 3625);
FORCEPROP 1 LAST OFFPAGE TRUE
J 2
(2625 3500);
DISPLAY 1.170213 (2625 3500);
PAINT GREEN (2625 3500);
DISPLAY INVISIBLE (2625 3500);
FORCEPROP 1 LAST COMMENT_BODY TRUE
J 2
(2825 3525);
DISPLAY 1.170213 (2825 3525);
PAINT GREEN (2825 3525);
DISPLAY INVISIBLE (2825 3525);
FORCEADD OFFPAGE..1
R 2
(2950 3775);
FORCEPROP 2 LAST $XR0 241 
J 0
(3136 3775);
DISPLAY 0.638298 (3136 3775);
PAINT MONO (3136 3775);
FORCEPROP 2 LAST PATH I173
J 0
(3150 3825);
DISPLAY 1.021277 (3150 3825);
DISPLAY INVISIBLE (3150 3825);
FORCEPROP 2 LAST CDS_LIB standard
J 2
(2950 3775);
DISPLAY INVISIBLE (2950 3775);
FORCEPROP 1 LAST OFFPAGE TRUE
J 2
(2625 3650);
DISPLAY 0.872340 (2625 3650);
DISPLAY INVISIBLE (2625 3650);
FORCEPROP 1 LAST COMMENT_BODY TRUE
J 2
(2825 3675);
DISPLAY 1.170213 (2825 3675);
PAINT GREEN (2825 3675);
DISPLAY INVISIBLE (2825 3675);
FORCEADD OFFPAGE..3
(2950 3725);
FORCEPROP 2 LAST $XR0 241 
J 0
(3164 3725);
DISPLAY 0.638298 (3164 3725);
PAINT MONO (3164 3725);
FORCEPROP 1 LAST OFFPAGE TRUE
J 0
(3275 3600);
DISPLAY 0.872340 (3275 3600);
DISPLAY INVISIBLE (3275 3600);
FORCEPROP 1 LAST COMMENT_BODY TRUE
J 0
(2900 3625);
DISPLAY 0.872340 (2900 3625);
PAINT GREEN (2900 3625);
DISPLAY INVISIBLE (2900 3625);
FORCEPROP 2 LAST PATH I174
J 0
(3175 3775);
DISPLAY 1.021277 (3175 3775);
DISPLAY INVISIBLE (3175 3775);
FORCEPROP 2 LAST CDS_LIB standard
J 2
(2950 3725);
PAINT MONO (2950 3725);
DISPLAY INVISIBLE (2950 3725);
FORCEADD OFFPAGE..1
R 2
(2950 3675);
FORCEPROP 2 LAST $XR0 222 
J 0
(3166 3675);
DISPLAY 0.638298 (3166 3675);
PAINT MONO (3166 3675);
FORCEPROP 2 LAST PATH I175
J 0
(3175 3725);
DISPLAY 1.021277 (3175 3725);
DISPLAY INVISIBLE (3175 3725);
FORCEPROP 2 LAST CDS_LIB standard
J 0
(2950 3675);
DISPLAY INVISIBLE (2950 3675);
FORCEPROP 1 LAST COMMENT_BODY TRUE
J 2
(2825 3575);
DISPLAY 1.170213 (2825 3575);
PAINT GREEN (2825 3575);
DISPLAY INVISIBLE (2825 3575);
FORCEPROP 1 LAST OFFPAGE TRUE
J 2
(2625 3550);
DISPLAY 1.170213 (2625 3550);
PAINT GREEN (2625 3550);
DISPLAY INVISIBLE (2625 3550);
FORCEADD OFFPAGE..1
R 2
(2950 3875);
FORCEPROP 2 LAST $XR0 213 
J 0
(3136 3875);
DISPLAY 0.638298 (3136 3875);
PAINT MONO (3136 3875);
FORCEPROP 2 LAST PATH I176
J 0
(3150 3925);
DISPLAY 1.021277 (3150 3925);
DISPLAY INVISIBLE (3150 3925);
FORCEPROP 2 LAST CDS_LIB standard
J 2
(2950 3875);
DISPLAY INVISIBLE (2950 3875);
FORCEPROP 1 LAST COMMENT_BODY TRUE
J 2
(2825 3775);
DISPLAY 1.170213 (2825 3775);
PAINT GREEN (2825 3775);
DISPLAY INVISIBLE (2825 3775);
FORCEPROP 1 LAST OFFPAGE TRUE
J 2
(2625 3750);
DISPLAY 0.872340 (2625 3750);
DISPLAY INVISIBLE (2625 3750);
FORCEADD OFFPAGE..1
R 2
(2950 3825);
FORCEPROP 2 LAST $XR0 260 
J 0
(3136 3825);
DISPLAY 0.638298 (3136 3825);
PAINT MONO (3136 3825);
FORCEPROP 2 LAST PATH I177
J 0
(3150 3875);
DISPLAY 1.021277 (3150 3875);
DISPLAY INVISIBLE (3150 3875);
FORCEPROP 1 LAST OFFPAGE TRUE
J 2
(2625 3700);
DISPLAY 0.872340 (2625 3700);
DISPLAY INVISIBLE (2625 3700);
FORCEPROP 1 LAST COMMENT_BODY TRUE
J 2
(2825 3725);
DISPLAY 1.170213 (2825 3725);
PAINT GREEN (2825 3725);
DISPLAY INVISIBLE (2825 3725);
FORCEPROP 2 LAST CDS_LIB standard
J 2
(2950 3825);
DISPLAY INVISIBLE (2950 3825);
FORCEADD Q_RES..2
R 2
(2750 4150);
FORCEPROP 1 LAST PART_NUMBER CS24702FB06
J 2
(2710 4025);
DISPLAY 0.638298 (2710 4025);
DISPLAY INVISIBLE (2710 4025);
FORCEPROP 1 LAST WATTAGE 1/16W
J 2
(2710 4125);
DISPLAY 0.638298 (2710 4125);
FORCEPROP 1 LAST MATERIAL EMPTY
J 2
(2710 4075);
DISPLAY 0.638298 (2710 4075);
PAINT RED (2710 4075);
FORCEPROP 1 LAST PACK_TYPE 0402LF
J 2
(2700 4025);
DISPLAY 0.638298 (2700 4025);
FORCEPROP 1 LAST VALUE 4.7K
J 2
(2705 4225);
DISPLAY 0.638298 (2705 4225);
FORCEPROP 1 LAST TOLERANCE 1%
J 2
(2705 4175);
DISPLAY 0.638298 (2705 4175);
FORCEPROP 1 LAST $LOCATION R1467
J 2
(2705 4275);
DISPLAY 0.978723 (2705 4275);
FORCEPROP 1 LASTPIN (2750 4250) $PN 1
J 2
(2745 4212);
DISPLAY 0.787234 (2745 4212);
FORCEPROP 1 LASTPIN (2750 4050) $PN 2
J 2
(2745 4060);
DISPLAY 0.787234 (2745 4060);
FORCEPROP 1 LAST PATH I178
J 2
(2700 4325);
DISPLAY 0.978723 (2700 4325);
PAINT WHITE (2700 4325);
DISPLAY INVISIBLE (2700 4325);
FORCEPROP 2 LAST CDS_LIB pure_quanta
J 2
(2750 4150);
PAINT MONO (2750 4150);
DISPLAY INVISIBLE (2750 4150);
FORCEPROP 2 LAST CDS_LOCATION R1467
J 2
(2700 4375);
DISPLAY 1.021277 (2700 4375);
DISPLAY INVISIBLE (2700 4375);
FORCEPROP 2 LAST $SEC 1
J 2
(2700 4375);
DISPLAY 0.680851 (2700 4375);
PAINT MONO (2700 4375);
DISPLAY INVISIBLE (2700 4375);
FORCEPROP 2 LAST CDS_SEC 1
J 2
(2700 4375);
DISPLAY 1.021277 (2700 4375);
DISPLAY INVISIBLE (2700 4375);
FORCEADD Q_RES..2
(2825 4150);
FORCEPROP 1 LAST PART_NUMBER CS24702FB06
J 0
(2885 3975);
DISPLAY 0.638298 (2885 3975);
DISPLAY INVISIBLE (2885 3975);
FORCEPROP 1 LAST PACK_TYPE 0402LF
J 0
(2875 4025);
DISPLAY 0.638298 (2875 4025);
FORCEPROP 1 LAST MATERIAL EMPTY
J 0
(2865 4075);
DISPLAY 0.638298 (2865 4075);
PAINT RED (2865 4075);
FORCEPROP 1 LAST WATTAGE 1/16W
J 0
(2865 4125);
DISPLAY 0.638298 (2865 4125);
FORCEPROP 1 LAST VALUE 4.7K
J 0
(2870 4225);
DISPLAY 0.638298 (2870 4225);
FORCEPROP 1 LAST TOLERANCE 1%
J 0
(2870 4175);
DISPLAY 0.638298 (2870 4175);
FORCEPROP 1 LAST $LOCATION R1551
J 0
(2870 4275);
DISPLAY 0.978723 (2870 4275);
FORCEPROP 1 LASTPIN (2825 4250) $PN 1
J 0
(2830 4212);
DISPLAY 0.787234 (2830 4212);
FORCEPROP 1 LASTPIN (2825 4050) $PN 2
J 0
(2830 4060);
DISPLAY 0.787234 (2830 4060);
FORCEPROP 1 LAST PATH I179
J 0
(2875 4325);
DISPLAY 0.978723 (2875 4325);
PAINT WHITE (2875 4325);
DISPLAY INVISIBLE (2875 4325);
FORCEPROP 2 LAST CDS_LIB pure_quanta
J 0
(2825 4150);
PAINT MONO (2825 4150);
DISPLAY INVISIBLE (2825 4150);
FORCEPROP 2 LAST CDS_LOCATION R1551
J 0
(2875 4375);
DISPLAY 1.021277 (2875 4375);
DISPLAY INVISIBLE (2875 4375);
FORCEPROP 2 LAST $SEC 1
J 0
(2875 4375);
DISPLAY 0.680851 (2875 4375);
PAINT MONO (2875 4375);
DISPLAY INVISIBLE (2875 4375);
FORCEPROP 2 LAST CDS_SEC 1
J 0
(2875 4375);
DISPLAY 1.021277 (2875 4375);
DISPLAY INVISIBLE (2875 4375);
FORCEADD Q_RES..1
(-2225 -1250);
FORCEPROP 1 LAST PART_NUMBER CS03322FB03
J 0
(-2375 -1175);
DISPLAY 0.638298 (-2375 -1175);
DISPLAY INVISIBLE (-2375 -1175);
FORCEPROP 1 LAST VALUE 33.2
J 2
(-1975 -1250);
DISPLAY 0.638298 (-1975 -1250);
FORCEPROP 1 LAST MATERIAL CHIP
J 0
(-1950 -1250);
DISPLAY 0.638298 (-1950 -1250);
FORCEPROP 1 LAST LOCATION R3485
J 0
(-2475 -1250);
DISPLAY 0.638298 (-2475 -1250);
FORCEPROP 1 LASTPIN (-2325 -1250) $PN 1
J 0
(-2313 -1238);
DISPLAY 0.787234 (-2313 -1238);
PAINT MONO (-2313 -1238);
FORCEPROP 1 LASTPIN (-2125 -1250) $PN 2
J 0
(-2163 -1238);
DISPLAY 0.787234 (-2163 -1238);
PAINT MONO (-2163 -1238);
FORCEPROP 1 LAST PATH I18
J 0
(-2275 -1100);
DISPLAY 0.978723 (-2275 -1100);
PAINT WHITE (-2275 -1100);
DISPLAY INVISIBLE (-2275 -1100);
FORCEPROP 2 LAST CDS_LIB pure_quanta
J 0
(-2225 -1250);
DISPLAY INVISIBLE (-2225 -1250);
FORCEPROP 1 LAST WATTAGE 1/16W
J 2
(-2025 -1125);
DISPLAY 0.638298 (-2025 -1125);
DISPLAY INVISIBLE (-2025 -1125);
FORCEPROP 1 LAST PACK_TYPE 0402LF
J 0
(-2375 -1125);
DISPLAY 0.638298 (-2375 -1125);
DISPLAY INVISIBLE (-2375 -1125);
FORCEPROP 1 LAST TOLERANCE 1%
J 0
(-1950 -1250);
DISPLAY 0.638298 (-1950 -1250);
DISPLAY INVISIBLE (-1950 -1250);
FORCEPROP 0 LAST $SEC 1
J 0
(-1950 -1200);
DISPLAY 0.680851 (-1950 -1200);
PAINT MONO (-1950 -1200);
DISPLAY INVISIBLE (-1950 -1200);
FORCEPROP 0 LAST CDS_SEC 1
J 0
(-1950 -1200);
DISPLAY 1.021277 (-1950 -1200);
DISPLAY INVISIBLE (-1950 -1200);
FORCEADD UNIVERSAL_POWER..1
(2825 4475);
FORCEPROP 3 LASTPIN (2825 4425) SIG_NAME P3V3_AUX\g
J 0
(2835 4435);
DISPLAY 0.659574 (2835 4435);
PAINT MONO (2835 4435);
DISPLAY INVISIBLE (2835 4435);
FORCEPROP 1 LAST HDL_POWER P3V3_AUX
J 1
(2825 4525);
DISPLAY 0.872340 (2825 4525);
PAINT GREEN (2825 4525);
FORCEPROP 1 LAST PATH I180
J 0
(2875 4500);
DISPLAY 0.872340 (2875 4500);
PAINT AQUA (2875 4500);
DISPLAY INVISIBLE (2875 4500);
FORCEPROP 2 LAST CDS_LIB logical_power
J 0
(2825 4475);
PAINT MONO (2825 4475);
DISPLAY INVISIBLE (2825 4475);
FORCEADD OFFPAGE..2
(3950 125);
FORCEPROP 2 LAST $XR0 213 
J 0
(4139 125);
DISPLAY 0.638298 (4139 125);
PAINT MONO (4139 125);
FORCEPROP 2 LAST PATH I181
J 0
(4150 175);
DISPLAY 1.021277 (4150 175);
DISPLAY INVISIBLE (4150 175);
FORCEPROP 2 LAST CDS_LIB standard
J 0
(3950 125);
PAINT MONO (3950 125);
DISPLAY INVISIBLE (3950 125);
FORCEPROP 1 LAST COMMENT_BODY TRUE
J 0
(3905 30);
DISPLAY 0.872340 (3905 30);
PAINT PEACH (3905 30);
DISPLAY INVISIBLE (3905 30);
FORCEPROP 1 LAST OFFPAGE TRUE
J 0
(4275 0);
DISPLAY 0.872340 (4275 0);
PAINT GREEN (4275 0);
DISPLAY INVISIBLE (4275 0);
FORCEADD OFFPAGE..2
(3950 300);
FORCEPROP 2 LAST $XR0 151 
J 0
(4139 300);
DISPLAY 0.638298 (4139 300);
PAINT MONO (4139 300);
FORCEPROP 2 LAST PATH I182
J 0
(4150 350);
DISPLAY 1.021277 (4150 350);
DISPLAY INVISIBLE (4150 350);
FORCEPROP 1 LAST COMMENT_BODY TRUE
J 0
(3905 205);
DISPLAY 0.872340 (3905 205);
PAINT PEACH (3905 205);
DISPLAY INVISIBLE (3905 205);
FORCEPROP 1 LAST OFFPAGE TRUE
J 0
(4275 175);
DISPLAY 0.872340 (4275 175);
PAINT GREEN (4275 175);
DISPLAY INVISIBLE (4275 175);
FORCEPROP 2 LAST CDS_LIB standard
J 0
(3950 300);
PAINT MONO (3950 300);
DISPLAY INVISIBLE (3950 300);
FORCEADD OFFPAGE..2
(3950 450);
FORCEPROP 2 LAST $XR0 185 
J 0
(4139 450);
DISPLAY 0.638298 (4139 450);
PAINT MONO (4139 450);
FORCEPROP 2 LAST PATH I183
J 0
(4150 500);
DISPLAY 1.021277 (4150 500);
DISPLAY INVISIBLE (4150 500);
FORCEPROP 2 LAST CDS_LIB standard
J 0
(3950 450);
PAINT MONO (3950 450);
DISPLAY INVISIBLE (3950 450);
FORCEPROP 1 LAST COMMENT_BODY TRUE
J 0
(3905 355);
DISPLAY 0.872340 (3905 355);
PAINT PEACH (3905 355);
DISPLAY INVISIBLE (3905 355);
FORCEPROP 1 LAST OFFPAGE TRUE
J 0
(4275 325);
DISPLAY 0.872340 (4275 325);
PAINT GREEN (4275 325);
DISPLAY INVISIBLE (4275 325);
FORCEADD OFFPAGE..2
(3950 575);
FORCEPROP 2 LAST $XR0 242 
J 0
(4139 575);
DISPLAY 0.638298 (4139 575);
PAINT MONO (4139 575);
FORCEPROP 2 LAST PATH I184
J 0
(4150 625);
DISPLAY 1.021277 (4150 625);
DISPLAY INVISIBLE (4150 625);
FORCEPROP 1 LAST COMMENT_BODY TRUE
J 0
(3905 480);
DISPLAY 0.872340 (3905 480);
PAINT PEACH (3905 480);
DISPLAY INVISIBLE (3905 480);
FORCEPROP 1 LAST OFFPAGE TRUE
J 0
(4275 450);
DISPLAY 0.872340 (4275 450);
PAINT GREEN (4275 450);
DISPLAY INVISIBLE (4275 450);
FORCEPROP 2 LAST CDS_LIB standard
J 0
(3950 575);
PAINT MONO (3950 575);
DISPLAY INVISIBLE (3950 575);
FORCEADD OFFPAGE..2
(3950 700);
FORCEPROP 2 LAST $XR0 184 
J 0
(4139 700);
DISPLAY 0.638298 (4139 700);
PAINT MONO (4139 700);
FORCEPROP 2 LAST PATH I185
J 0
(4150 750);
DISPLAY 1.021277 (4150 750);
DISPLAY INVISIBLE (4150 750);
FORCEPROP 1 LAST OFFPAGE TRUE
J 0
(4275 575);
DISPLAY 0.872340 (4275 575);
PAINT GREEN (4275 575);
DISPLAY INVISIBLE (4275 575);
FORCEPROP 1 LAST COMMENT_BODY TRUE
J 0
(3905 605);
DISPLAY 0.872340 (3905 605);
PAINT PEACH (3905 605);
DISPLAY INVISIBLE (3905 605);
FORCEPROP 2 LAST CDS_LIB standard
J 0
(3950 700);
PAINT MONO (3950 700);
DISPLAY INVISIBLE (3950 700);
FORCEADD OFFPAGE..2
(3950 825);
FORCEPROP 2 LAST $XR0 206 
J 0
(4139 825);
DISPLAY 0.638298 (4139 825);
PAINT MONO (4139 825);
FORCEPROP 2 LAST PATH I186
J 0
(4150 875);
DISPLAY 1.021277 (4150 875);
DISPLAY INVISIBLE (4150 875);
FORCEPROP 2 LAST CDS_LIB standard
J 0
(3950 825);
DISPLAY INVISIBLE (3950 825);
FORCEPROP 1 LAST COMMENT_BODY TRUE
J 0
(3905 730);
DISPLAY 0.872340 (3905 730);
PAINT PEACH (3905 730);
DISPLAY INVISIBLE (3905 730);
FORCEPROP 1 LAST OFFPAGE TRUE
J 0
(4275 700);
DISPLAY 0.872340 (4275 700);
PAINT GREEN (4275 700);
DISPLAY INVISIBLE (4275 700);
FORCEADD OFFPAGE..1
R 2
(3950 950);
FORCEPROP 2 LAST $XR0 213 
J 0
(4136 950);
DISPLAY 0.638298 (4136 950);
PAINT MONO (4136 950);
FORCEPROP 2 LAST PATH I187
J 0
(4150 1000);
DISPLAY 1.021277 (4150 1000);
DISPLAY INVISIBLE (4150 1000);
FORCEPROP 1 LAST OFFPAGE TRUE
J 2
(3625 825);
DISPLAY 0.872340 (3625 825);
DISPLAY INVISIBLE (3625 825);
FORCEPROP 1 LAST COMMENT_BODY TRUE
J 2
(3825 850);
DISPLAY 1.170213 (3825 850);
PAINT GREEN (3825 850);
DISPLAY INVISIBLE (3825 850);
FORCEPROP 2 LAST CDS_LIB standard
J 2
(3950 950);
DISPLAY INVISIBLE (3950 950);
FORCEADD LCMXO3LF9400C5BG484C..3
(800 2675);
FORCEPROP 1 LAST PART_NUMBER AJ094000T08
J 0
(-93 4071);
DISPLAY 0.723404 (-93 4071);
PAINT GREEN (-93 4071);
DISPLAY INVISIBLE (-93 4071);
FORCEPROP 1 LAST MATERIAL IC
J 0
(-93 3944);
DISPLAY 0.723404 (-93 3944);
PAINT GREEN (-93 3944);
FORCEPROP 2 LAST VALUE LCMXO3LF-9400C-5BG484C
J 0
(-75 4275);
DISPLAY 1.021277 (-75 4275);
FORCEPROP 2 LAST PART_TYPE SMLF
J 0
(-75 4325);
DISPLAY 1.021277 (-75 4325);
FORCEPROP 1 LAST $LOCATION U249
J 0
(-93 4218);
DISPLAY 0.723404 (-93 4218);
PAINT GREEN (-93 4218);
FORCEPROP 0 LASTPIN (-250 3825) $PN B1
J 2
(-260 3835);
DISPLAY 0.680851 (-260 3835);
PAINT MONO (-260 3835);
FORCEPROP 0 LASTPIN (-250 3775) $PN A2
J 2
(-260 3785);
DISPLAY 0.680851 (-260 3785);
PAINT MONO (-260 3785);
FORCEPROP 0 LASTPIN (-250 3725) $PN E6
J 2
(-260 3735);
DISPLAY 0.680851 (-260 3735);
PAINT MONO (-260 3735);
FORCEPROP 0 LASTPIN (-250 3675) $PN F7
J 2
(-260 3685);
DISPLAY 0.680851 (-260 3685);
PAINT MONO (-260 3685);
FORCEPROP 0 LASTPIN (-250 3625) $PN B2
J 2
(-260 3635);
DISPLAY 0.680851 (-260 3635);
PAINT MONO (-260 3635);
FORCEPROP 0 LASTPIN (-250 3575) $PN A3
J 2
(-260 3585);
DISPLAY 0.680851 (-260 3585);
PAINT MONO (-260 3585);
FORCEPROP 0 LASTPIN (-250 3525) $PN C3
J 2
(-260 3535);
DISPLAY 0.680851 (-260 3535);
PAINT MONO (-260 3535);
FORCEPROP 0 LASTPIN (-250 3475) $PN C4
J 2
(-260 3485);
DISPLAY 0.680851 (-260 3485);
PAINT MONO (-260 3485);
FORCEPROP 0 LASTPIN (-250 3425) $PN B3
J 2
(-260 3435);
DISPLAY 0.680851 (-260 3435);
PAINT MONO (-260 3435);
FORCEPROP 0 LASTPIN (-250 3375) $PN A4
J 2
(-260 3385);
DISPLAY 0.680851 (-260 3385);
PAINT MONO (-260 3385);
FORCEPROP 0 LASTPIN (-250 3325) $PN F8
J 2
(-260 3335);
DISPLAY 0.680851 (-260 3335);
PAINT MONO (-260 3335);
FORCEPROP 0 LASTPIN (-250 3275) $PN G8
J 2
(-260 3285);
DISPLAY 0.680851 (-260 3285);
PAINT MONO (-260 3285);
FORCEPROP 0 LASTPIN (-250 3225) $PN B4
J 2
(-260 3235);
DISPLAY 0.680851 (-260 3235);
PAINT MONO (-260 3235);
FORCEPROP 0 LASTPIN (-250 3175) $PN A5
J 2
(-260 3185);
DISPLAY 0.680851 (-260 3185);
PAINT MONO (-260 3185);
FORCEPROP 0 LASTPIN (-250 3125) $PN D5
J 2
(-260 3135);
DISPLAY 0.680851 (-260 3135);
PAINT MONO (-260 3135);
FORCEPROP 0 LASTPIN (-250 3075) $PN C5
J 2
(-260 3085);
DISPLAY 0.680851 (-260 3085);
PAINT MONO (-260 3085);
FORCEPROP 0 LASTPIN (-250 3025) $PN B5
J 2
(-260 3035);
DISPLAY 0.680851 (-260 3035);
PAINT MONO (-260 3035);
FORCEPROP 0 LASTPIN (-250 2975) $PN A6
J 2
(-260 2985);
DISPLAY 0.680851 (-260 2985);
PAINT MONO (-260 2985);
FORCEPROP 0 LASTPIN (-250 2925) $PN D6
J 2
(-260 2935);
DISPLAY 0.680851 (-260 2935);
PAINT MONO (-260 2935);
FORCEPROP 0 LASTPIN (-250 2875) $PN E7
J 2
(-260 2885);
DISPLAY 0.680851 (-260 2885);
PAINT MONO (-260 2885);
FORCEPROP 0 LASTPIN (-250 2825) $PN B6
J 2
(-260 2835);
DISPLAY 0.680851 (-260 2835);
PAINT MONO (-260 2835);
FORCEPROP 0 LASTPIN (-250 2775) $PN A7
J 2
(-260 2785);
DISPLAY 0.680851 (-260 2785);
PAINT MONO (-260 2785);
FORCEPROP 0 LASTPIN (-250 2725) $PN C6
J 2
(-260 2735);
DISPLAY 0.680851 (-260 2735);
PAINT MONO (-260 2735);
FORCEPROP 0 LASTPIN (-250 2675) $PN D7
J 2
(-260 2685);
DISPLAY 0.680851 (-260 2685);
PAINT MONO (-260 2685);
FORCEPROP 0 LASTPIN (-250 2625) $PN C8
J 2
(-260 2635);
DISPLAY 0.680851 (-260 2635);
PAINT MONO (-260 2635);
FORCEPROP 0 LASTPIN (-250 2575) $PN D8
J 2
(-260 2585);
DISPLAY 0.680851 (-260 2585);
PAINT MONO (-260 2585);
FORCEPROP 0 LASTPIN (-250 2525) $PN B8
J 2
(-260 2535);
DISPLAY 0.680851 (-260 2535);
PAINT MONO (-260 2535);
FORCEPROP 0 LASTPIN (-250 2475) $PN A8
J 2
(-260 2485);
DISPLAY 0.680851 (-260 2485);
PAINT MONO (-260 2485);
FORCEPROP 0 LASTPIN (-250 2425) $PN C9
J 2
(-260 2435);
DISPLAY 0.680851 (-260 2435);
PAINT MONO (-260 2435);
FORCEPROP 0 LASTPIN (-250 2375) $PN D9
J 2
(-260 2385);
DISPLAY 0.680851 (-260 2385);
PAINT MONO (-260 2385);
FORCEPROP 0 LASTPIN (-250 2225) $PN B9
J 2
(-260 2235);
DISPLAY 0.680851 (-260 2235);
PAINT MONO (-260 2235);
FORCEPROP 0 LASTPIN (-250 2175) $PN A9
J 2
(-260 2185);
DISPLAY 0.680851 (-260 2185);
PAINT MONO (-260 2185);
FORCEPROP 0 LASTPIN (-250 2125) $PN F9
J 2
(-260 2135);
DISPLAY 0.680851 (-260 2135);
PAINT MONO (-260 2135);
FORCEPROP 0 LASTPIN (-250 2075) $PN G9
J 2
(-260 2085);
DISPLAY 0.680851 (-260 2085);
PAINT MONO (-260 2085);
FORCEPROP 0 LASTPIN (-250 2025) $PN F10
J 2
(-260 2035);
DISPLAY 0.680851 (-260 2035);
PAINT MONO (-260 2035);
FORCEPROP 0 LASTPIN (-250 1975) $PN E10
J 2
(-260 1985);
DISPLAY 0.680851 (-260 1985);
PAINT MONO (-260 1985);
FORCEPROP 0 LASTPIN (-250 1925) $PN B10
J 2
(-260 1935);
DISPLAY 0.680851 (-260 1935);
PAINT MONO (-260 1935);
FORCEPROP 0 LASTPIN (-250 1875) $PN A10
J 2
(-260 1885);
DISPLAY 0.680851 (-260 1885);
PAINT MONO (-260 1885);
FORCEPROP 0 LASTPIN (-250 1825) $PN G11
J 2
(-260 1835);
DISPLAY 0.680851 (-260 1835);
PAINT MONO (-260 1835);
FORCEPROP 0 LASTPIN (-250 1775) $PN F11
J 2
(-260 1785);
DISPLAY 0.680851 (-260 1785);
PAINT MONO (-260 1785);
FORCEPROP 0 LASTPIN (-250 1675) $PN B11
J 2
(-260 1685);
DISPLAY 0.680851 (-260 1685);
PAINT MONO (-260 1685);
FORCEPROP 0 LASTPIN (-250 1625) $PN A11
J 2
(-260 1635);
DISPLAY 0.680851 (-260 1635);
PAINT MONO (-260 1635);
FORCEPROP 0 LASTPIN (-250 1575) $PN E11
J 2
(-260 1585);
DISPLAY 0.680851 (-260 1585);
PAINT MONO (-260 1585);
FORCEPROP 0 LASTPIN (-250 1525) $PN D11
J 2
(-260 1535);
DISPLAY 0.680851 (-260 1535);
PAINT MONO (-260 1535);
FORCEPROP 0 LASTPIN (1850 3875) $PN D12
J 0
(1860 3885);
DISPLAY 0.680851 (1860 3885);
PAINT MONO (1860 3885);
FORCEPROP 0 LASTPIN (1850 3825) $PN E12
J 0
(1860 3835);
DISPLAY 0.680851 (1860 3835);
PAINT MONO (1860 3835);
FORCEPROP 0 LASTPIN (1850 3775) $PN B12
J 0
(1860 3785);
DISPLAY 0.680851 (1860 3785);
PAINT MONO (1860 3785);
FORCEPROP 0 LASTPIN (1850 3725) $PN A12
J 0
(1860 3735);
DISPLAY 0.680851 (1860 3735);
PAINT MONO (1860 3735);
FORCEPROP 0 LASTPIN (1850 3675) $PN G12
J 0
(1860 3685);
DISPLAY 0.680851 (1860 3685);
PAINT MONO (1860 3685);
FORCEPROP 0 LASTPIN (1850 3625) $PN F12
J 0
(1860 3635);
DISPLAY 0.680851 (1860 3635);
PAINT MONO (1860 3635);
FORCEPROP 0 LASTPIN (1850 3575) $PN E13
J 0
(1860 3585);
DISPLAY 0.680851 (1860 3585);
PAINT MONO (1860 3585);
FORCEPROP 0 LASTPIN (1850 3525) $PN F13
J 0
(1860 3535);
DISPLAY 0.680851 (1860 3535);
PAINT MONO (1860 3535);
FORCEPROP 0 LASTPIN (1850 3475) $PN A13
J 0
(1860 3485);
DISPLAY 0.680851 (1860 3485);
PAINT MONO (1860 3485);
FORCEPROP 0 LASTPIN (1850 3425) $PN B13
J 0
(1860 3435);
DISPLAY 0.680851 (1860 3435);
PAINT MONO (1860 3435);
FORCEPROP 0 LASTPIN (1850 3375) $PN C13
J 0
(1860 3385);
DISPLAY 0.680851 (1860 3385);
PAINT MONO (1860 3385);
FORCEPROP 0 LASTPIN (1850 3325) $PN D13
J 0
(1860 3335);
DISPLAY 0.680851 (1860 3335);
PAINT MONO (1860 3335);
FORCEPROP 0 LASTPIN (1850 3275) $PN A14
J 0
(1860 3285);
DISPLAY 0.680851 (1860 3285);
PAINT MONO (1860 3285);
FORCEPROP 0 LASTPIN (1850 3225) $PN B14
J 0
(1860 3235);
DISPLAY 0.680851 (1860 3235);
PAINT MONO (1860 3235);
FORCEPROP 0 LASTPIN (1850 3175) $PN C14
J 0
(1860 3185);
DISPLAY 0.680851 (1860 3185);
PAINT MONO (1860 3185);
FORCEPROP 0 LASTPIN (1850 3125) $PN D14
J 0
(1860 3135);
DISPLAY 0.680851 (1860 3135);
PAINT MONO (1860 3135);
FORCEPROP 0 LASTPIN (1850 3075) $PN G14
J 0
(1860 3085);
DISPLAY 0.680851 (1860 3085);
PAINT MONO (1860 3085);
FORCEPROP 0 LASTPIN (1850 3025) $PN F14
J 0
(1860 3035);
DISPLAY 0.680851 (1860 3035);
PAINT MONO (1860 3035);
FORCEPROP 0 LASTPIN (1850 2925) $PN A15
J 0
(1860 2935);
DISPLAY 0.680851 (1860 2935);
PAINT MONO (1860 2935);
FORCEPROP 0 LASTPIN (1850 2875) $PN B15
J 0
(1860 2885);
DISPLAY 0.680851 (1860 2885);
PAINT MONO (1860 2885);
FORCEPROP 0 LASTPIN (1850 2825) $PN C15
J 0
(1860 2835);
DISPLAY 0.680851 (1860 2835);
PAINT MONO (1860 2835);
FORCEPROP 0 LASTPIN (1850 2775) $PN D15
J 0
(1860 2785);
DISPLAY 0.680851 (1860 2785);
PAINT MONO (1860 2785);
FORCEPROP 0 LASTPIN (1850 2725) $PN A16
J 0
(1860 2735);
DISPLAY 0.680851 (1860 2735);
PAINT MONO (1860 2735);
FORCEPROP 0 LASTPIN (1850 2675) $PN B17
J 0
(1860 2685);
DISPLAY 0.680851 (1860 2685);
PAINT MONO (1860 2685);
FORCEPROP 0 LASTPIN (1850 2625) $PN C17
J 0
(1860 2635);
DISPLAY 0.680851 (1860 2635);
PAINT MONO (1860 2635);
FORCEPROP 0 LASTPIN (1850 2575) $PN D16
J 0
(1860 2585);
DISPLAY 0.680851 (1860 2585);
PAINT MONO (1860 2585);
FORCEPROP 0 LASTPIN (1850 2525) $PN A17
J 0
(1860 2535);
DISPLAY 0.680851 (1860 2535);
PAINT MONO (1860 2535);
FORCEPROP 0 LASTPIN (1850 2475) $PN B18
J 0
(1860 2485);
DISPLAY 0.680851 (1860 2485);
PAINT MONO (1860 2485);
FORCEPROP 0 LASTPIN (1850 2425) $PN E16
J 0
(1860 2435);
DISPLAY 0.680851 (1860 2435);
PAINT MONO (1860 2435);
FORCEPROP 0 LASTPIN (1850 2375) $PN D17
J 0
(1860 2385);
DISPLAY 0.680851 (1860 2385);
PAINT MONO (1860 2385);
FORCEPROP 0 LASTPIN (1850 2325) $PN A18
J 0
(1860 2335);
DISPLAY 0.680851 (1860 2335);
PAINT MONO (1860 2335);
FORCEPROP 0 LASTPIN (1850 2275) $PN B19
J 0
(1860 2285);
DISPLAY 0.680851 (1860 2285);
PAINT MONO (1860 2285);
FORCEPROP 0 LASTPIN (1850 2225) $PN C18
J 0
(1860 2235);
DISPLAY 0.680851 (1860 2235);
PAINT MONO (1860 2235);
FORCEPROP 0 LASTPIN (1850 2175) $PN D18
J 0
(1860 2185);
DISPLAY 0.680851 (1860 2185);
PAINT MONO (1860 2185);
FORCEPROP 0 LASTPIN (1850 2075) $PN A19
J 0
(1860 2085);
DISPLAY 0.680851 (1860 2085);
PAINT MONO (1860 2085);
FORCEPROP 0 LASTPIN (1850 2025) $PN B20
J 0
(1860 2035);
DISPLAY 0.680851 (1860 2035);
PAINT MONO (1860 2035);
FORCEPROP 0 LASTPIN (1850 1975) $PN F15
J 0
(1860 1985);
DISPLAY 0.680851 (1860 1985);
PAINT MONO (1860 1985);
FORCEPROP 0 LASTPIN (1850 1925) $PN G15
J 0
(1860 1935);
DISPLAY 0.680851 (1860 1935);
PAINT MONO (1860 1935);
FORCEPROP 0 LASTPIN (1850 1825) $PN A20
J 0
(1860 1835);
DISPLAY 0.680851 (1860 1835);
PAINT MONO (1860 1835);
FORCEPROP 0 LASTPIN (1850 1775) $PN B21
J 0
(1860 1785);
DISPLAY 0.680851 (1860 1785);
PAINT MONO (1860 1785);
FORCEPROP 0 LASTPIN (1850 1725) $PN C19
J 0
(1860 1735);
DISPLAY 0.680851 (1860 1735);
PAINT MONO (1860 1735);
FORCEPROP 0 LASTPIN (1850 1675) $PN C20
J 0
(1860 1685);
DISPLAY 0.680851 (1860 1685);
PAINT MONO (1860 1685);
FORCEPROP 0 LASTPIN (1850 1575) $PN A21
J 0
(1860 1585);
DISPLAY 0.680851 (1860 1585);
PAINT MONO (1860 1585);
FORCEPROP 0 LASTPIN (1850 1525) $PN B22
J 0
(1860 1535);
DISPLAY 0.680851 (1860 1535);
PAINT MONO (1860 1535);
FORCEPROP 1 LAST PATH I188
J 0
(800 2675);
DISPLAY 0.723404 (800 2675);
PAINT GREEN (800 2675);
DISPLAY INVISIBLE (800 2675);
FORCEPROP 2 LAST CDS_LIB pure_quanta
J 0
(800 2675);
DISPLAY INVISIBLE (800 2675);
FORCEPROP 1 LAST NEEDS_NO_SIZE TRUE
J 0
(800 2675);
DISPLAY 0.723404 (800 2675);
PAINT GREEN (800 2675);
DISPLAY INVISIBLE (800 2675);
FORCEPROP 1 LAST CDS_LMAN_SYM_OUTLINE -900,1250,900,-1250
J 0
(800 2675);
DISPLAY 0.468085 (800 2675);
PAINT GREEN (800 2675);
DISPLAY INVISIBLE (800 2675);
FORCEPROP 0 LAST CDS_LOCATION U249
J 0
(-75 4375);
DISPLAY 1.021277 (-75 4375);
DISPLAY INVISIBLE (-75 4375);
FORCEPROP 0 LAST $SEC 3
J 0
(-75 4375);
DISPLAY 0.680851 (-75 4375);
PAINT MONO (-75 4375);
DISPLAY INVISIBLE (-75 4375);
FORCEPROP 0 LAST CDS_SEC 3
J 0
(-75 4375);
DISPLAY 1.021277 (-75 4375);
DISPLAY INVISIBLE (-75 4375);
FORCEADD OFFPAGE..3
(-775 25);
FORCEPROP 2 LAST $XR0 213 
J 0
(-561 25);
DISPLAY 0.638298 (-561 25);
PAINT MONO (-561 25);
FORCEPROP 1 LAST OFFPAGE TRUE
J 0
(-450 -100);
DISPLAY 0.872340 (-450 -100);
PAINT GREEN (-450 -100);
DISPLAY INVISIBLE (-450 -100);
FORCEPROP 1 LAST COMMENT_BODY TRUE
J 0
(-825 -75);
DISPLAY 0.872340 (-825 -75);
PAINT GREEN (-825 -75);
DISPLAY INVISIBLE (-825 -75);
FORCEPROP 2 LAST CDS_LIB standard
J 0
(-775 25);
DISPLAY INVISIBLE (-775 25);
FORCEPROP 2 LAST PATH I189
J 0
(-575 100);
DISPLAY 1.021277 (-575 100);
DISPLAY INVISIBLE (-575 100);
FORCEADD Q_RES..1
(-2225 -875);
FORCEPROP 1 LAST PART_NUMBER CS03322FB03
J 0
(-2375 -800);
DISPLAY 0.638298 (-2375 -800);
DISPLAY INVISIBLE (-2375 -800);
FORCEPROP 1 LAST MATERIAL CHIP
J 0
(-1950 -875);
DISPLAY 0.638298 (-1950 -875);
FORCEPROP 1 LAST VALUE 33.2
J 2
(-1975 -875);
DISPLAY 0.638298 (-1975 -875);
FORCEPROP 1 LAST LOCATION R3482
J 0
(-2475 -875);
DISPLAY 0.638298 (-2475 -875);
FORCEPROP 1 LASTPIN (-2325 -875) $PN 1
J 0
(-2313 -863);
DISPLAY 0.787234 (-2313 -863);
PAINT MONO (-2313 -863);
FORCEPROP 1 LASTPIN (-2125 -875) $PN 2
J 0
(-2163 -863);
DISPLAY 0.787234 (-2163 -863);
PAINT MONO (-2163 -863);
FORCEPROP 1 LAST PATH I19
J 0
(-2275 -725);
DISPLAY 0.978723 (-2275 -725);
PAINT WHITE (-2275 -725);
DISPLAY INVISIBLE (-2275 -725);
FORCEPROP 2 LAST CDS_LIB pure_quanta
J 0
(-2225 -875);
DISPLAY INVISIBLE (-2225 -875);
FORCEPROP 1 LAST WATTAGE 1/16W
J 2
(-2025 -750);
DISPLAY 0.638298 (-2025 -750);
DISPLAY INVISIBLE (-2025 -750);
FORCEPROP 1 LAST PACK_TYPE 0402LF
J 0
(-2375 -750);
DISPLAY 0.638298 (-2375 -750);
DISPLAY INVISIBLE (-2375 -750);
FORCEPROP 1 LAST TOLERANCE 1%
J 0
(-1950 -875);
DISPLAY 0.638298 (-1950 -875);
DISPLAY INVISIBLE (-1950 -875);
FORCEPROP 0 LAST $SEC 1
J 0
(-1950 -825);
DISPLAY 0.680851 (-1950 -825);
PAINT MONO (-1950 -825);
DISPLAY INVISIBLE (-1950 -825);
FORCEPROP 0 LAST CDS_SEC 1
J 0
(-1950 -825);
DISPLAY 1.021277 (-1950 -825);
DISPLAY INVISIBLE (-1950 -825);
FORCEADD OFFPAGE..2
(-775 100);
FORCEPROP 2 LAST $XR0 213 
J 0
(-586 100);
DISPLAY 0.638298 (-586 100);
PAINT MONO (-586 100);
FORCEPROP 2 LAST PATH I190
J 0
(-600 175);
DISPLAY 1.021277 (-600 175);
DISPLAY INVISIBLE (-600 175);
FORCEPROP 1 LAST COMMENT_BODY TRUE
J 0
(-820 5);
DISPLAY 0.872340 (-820 5);
PAINT GREEN (-820 5);
DISPLAY INVISIBLE (-820 5);
FORCEPROP 1 LAST OFFPAGE TRUE
J 0
(-450 -25);
DISPLAY 0.872340 (-450 -25);
PAINT GREEN (-450 -25);
DISPLAY INVISIBLE (-450 -25);
FORCEPROP 2 LAST CDS_LIB standard
J 0
(-775 100);
DISPLAY INVISIBLE (-775 100);
FORCEADD OFFPAGE..1
(-3425 25);
FORCEPROP 2 LAST $XR1 241 
J 0
(-3797 25);
DISPLAY 0.638298 (-3797 25);
PAINT MONO (-3797 25);
FORCEPROP 2 LAST $XR0 131 
J 0
(-3677 25);
DISPLAY 0.638298 (-3677 25);
PAINT MONO (-3677 25);
FORCEPROP 2 LAST CDS_LIB standard
J 0
(-3425 25);
DISPLAY INVISIBLE (-3425 25);
FORCEPROP 1 LAST OFFPAGE TRUE
J 0
(-3100 -100);
DISPLAY 0.872340 (-3100 -100);
PAINT GREEN (-3100 -100);
DISPLAY INVISIBLE (-3100 -100);
FORCEPROP 1 LAST COMMENT_BODY TRUE
J 0
(-3300 -75);
DISPLAY 0.872340 (-3300 -75);
PAINT GREEN (-3300 -75);
DISPLAY INVISIBLE (-3300 -75);
FORCEPROP 2 LAST PATH I193
J 0
(-3700 75);
DISPLAY 1.021277 (-3700 75);
DISPLAY INVISIBLE (-3700 75);
FORCEADD OFFPAGE..3
R 2
(-3425 100);
FORCEPROP 2 LAST $XR1 241 
J 0
(-3825 100);
DISPLAY 0.638298 (-3825 100);
PAINT MONO (-3825 100);
FORCEPROP 2 LAST $XR0 131 
J 0
(-3705 100);
DISPLAY 0.638298 (-3705 100);
PAINT MONO (-3705 100);
FORCEPROP 2 LAST PATH I194
J 0
(-3700 150);
DISPLAY 1.021277 (-3700 150);
DISPLAY INVISIBLE (-3700 150);
FORCEPROP 1 LAST OFFPAGE TRUE
J 2
(-3750 -25);
DISPLAY 0.872340 (-3750 -25);
DISPLAY INVISIBLE (-3750 -25);
FORCEPROP 1 LAST COMMENT_BODY TRUE
J 2
(-3375 0);
DISPLAY 0.872340 (-3375 0);
PAINT GREEN (-3375 0);
DISPLAY INVISIBLE (-3375 0);
FORCEPROP 2 LAST CDS_LIB standard
J 0
(-3425 100);
DISPLAY INVISIBLE (-3425 100);
FORCEADD OFFPAGE..1
(-1500 1875);
FORCEPROP 2 LAST $XR0 213 
J 0
(-1782 1875);
DISPLAY 0.638298 (-1782 1875);
PAINT MONO (-1782 1875);
FORCEPROP 2 LAST PATH I195
J 0
(-1450 1950);
DISPLAY 1.021277 (-1450 1950);
DISPLAY INVISIBLE (-1450 1950);
FORCEPROP 2 LAST CDS_LIB standard
J 0
(-1500 1875);
DISPLAY INVISIBLE (-1500 1875);
FORCEPROP 1 LAST COMMENT_BODY TRUE
J 0
(-1375 1775);
DISPLAY 1.170213 (-1375 1775);
PAINT GREEN (-1375 1775);
DISPLAY INVISIBLE (-1375 1775);
FORCEPROP 1 LAST OFFPAGE TRUE
J 0
(-1175 1750);
DISPLAY 1.170213 (-1175 1750);
PAINT GREEN (-1175 1750);
DISPLAY INVISIBLE (-1175 1750);
FORCEADD OFFPAGE..3
R 2
(-1500 1925);
FORCEPROP 2 LAST $XR0 213 
J 0
(-1780 1925);
DISPLAY 0.638298 (-1780 1925);
PAINT MONO (-1780 1925);
FORCEPROP 1 LAST COMMENT_BODY TRUE
J 2
(-1450 1825);
DISPLAY 0.872340 (-1450 1825);
PAINT GREEN (-1450 1825);
DISPLAY INVISIBLE (-1450 1825);
FORCEPROP 1 LAST OFFPAGE TRUE
J 2
(-1825 1800);
DISPLAY 0.872340 (-1825 1800);
DISPLAY INVISIBLE (-1825 1800);
FORCEPROP 2 LAST PATH I196
J 2
(-1700 2000);
DISPLAY 1.021277 (-1700 2000);
DISPLAY INVISIBLE (-1700 2000);
FORCEPROP 2 LAST CDS_LIB standard
J 2
(-1500 1925);
DISPLAY INVISIBLE (-1500 1925);
FORCEADD Q_RES..1
(-2225 100);
FORCEPROP 1 LAST PART_NUMBER CS03322FB03
J 0
(-2375 175);
DISPLAY 0.638298 (-2375 175);
DISPLAY INVISIBLE (-2375 175);
FORCEPROP 1 LAST VALUE 33.2
J 2
(-1975 100);
DISPLAY 0.638298 (-1975 100);
FORCEPROP 1 LAST MATERIAL CHIP
J 0
(-1950 100);
DISPLAY 0.638298 (-1950 100);
FORCEPROP 1 LAST LOCATION R4714
J 0
(-2475 100);
DISPLAY 0.638298 (-2475 100);
FORCEPROP 1 LASTPIN (-2325 100) $PN 1
J 0
(-2313 112);
DISPLAY 0.787234 (-2313 112);
PAINT MONO (-2313 112);
FORCEPROP 1 LASTPIN (-2125 100) $PN 2
J 0
(-2163 112);
DISPLAY 0.787234 (-2163 112);
PAINT MONO (-2163 112);
FORCEPROP 2 LAST CDS_LIB pure_quanta
J 0
(-2225 100);
DISPLAY INVISIBLE (-2225 100);
FORCEPROP 1 LAST PATH I197
J 0
(-2275 250);
DISPLAY 0.978723 (-2275 250);
PAINT WHITE (-2275 250);
DISPLAY INVISIBLE (-2275 250);
FORCEPROP 1 LAST TOLERANCE 1%
J 0
(-1950 100);
DISPLAY 0.638298 (-1950 100);
DISPLAY INVISIBLE (-1950 100);
FORCEPROP 1 LAST PACK_TYPE 0402LF
J 0
(-2375 225);
DISPLAY 0.638298 (-2375 225);
DISPLAY INVISIBLE (-2375 225);
FORCEPROP 1 LAST WATTAGE 1/16W
J 2
(-2025 225);
DISPLAY 0.638298 (-2025 225);
DISPLAY INVISIBLE (-2025 225);
FORCEPROP 0 LAST $SEC 1
J 0
(-1950 150);
DISPLAY 0.680851 (-1950 150);
PAINT MONO (-1950 150);
DISPLAY INVISIBLE (-1950 150);
FORCEPROP 0 LAST CDS_SEC 1
J 0
(-1950 150);
DISPLAY 1.021277 (-1950 150);
DISPLAY INVISIBLE (-1950 150);
FORCEADD Q_RES..1
(-2225 25);
FORCEPROP 1 LAST PART_NUMBER CS03322FB03
J 0
(-2375 100);
DISPLAY 0.638298 (-2375 100);
DISPLAY INVISIBLE (-2375 100);
FORCEPROP 1 LAST VALUE 33.2
J 2
(-1975 25);
DISPLAY 0.638298 (-1975 25);
FORCEPROP 1 LAST MATERIAL CHIP
J 0
(-1950 25);
DISPLAY 0.638298 (-1950 25);
FORCEPROP 1 LAST LOCATION R4715
J 0
(-2475 25);
DISPLAY 0.638298 (-2475 25);
FORCEPROP 1 LASTPIN (-2325 25) $PN 1
J 0
(-2313 37);
DISPLAY 0.787234 (-2313 37);
PAINT MONO (-2313 37);
FORCEPROP 1 LASTPIN (-2125 25) $PN 2
J 0
(-2163 37);
DISPLAY 0.787234 (-2163 37);
PAINT MONO (-2163 37);
FORCEPROP 1 LAST WATTAGE 1/16W
J 2
(-2025 150);
DISPLAY 0.638298 (-2025 150);
DISPLAY INVISIBLE (-2025 150);
FORCEPROP 1 LAST PACK_TYPE 0402LF
J 0
(-2375 150);
DISPLAY 0.638298 (-2375 150);
DISPLAY INVISIBLE (-2375 150);
FORCEPROP 1 LAST TOLERANCE 1%
J 0
(-1950 25);
DISPLAY 0.638298 (-1950 25);
DISPLAY INVISIBLE (-1950 25);
FORCEPROP 1 LAST PATH I198
J 0
(-2275 175);
DISPLAY 0.978723 (-2275 175);
PAINT WHITE (-2275 175);
DISPLAY INVISIBLE (-2275 175);
FORCEPROP 2 LAST CDS_LIB pure_quanta
J 0
(-2225 25);
DISPLAY INVISIBLE (-2225 25);
FORCEPROP 0 LAST $SEC 1
J 0
(-1950 75);
DISPLAY 0.680851 (-1950 75);
PAINT MONO (-1950 75);
DISPLAY INVISIBLE (-1950 75);
FORCEPROP 0 LAST CDS_SEC 1
J 0
(-1950 75);
DISPLAY 1.021277 (-1950 75);
DISPLAY INVISIBLE (-1950 75);
FORCEADD OFFPAGE..1
(-3425 -1500);
FORCEPROP 2 LAST $XR0 147 
J 0
(-3677 -1500);
DISPLAY 0.638298 (-3677 -1500);
PAINT MONO (-3677 -1500);
FORCEPROP 2 LAST PATH I2
J 0
(-3675 -1450);
DISPLAY 1.021277 (-3675 -1450);
DISPLAY INVISIBLE (-3675 -1450);
FORCEPROP 2 LAST CDS_LIB standard
J 0
(-3425 -1500);
DISPLAY INVISIBLE (-3425 -1500);
FORCEPROP 1 LAST COMMENT_BODY TRUE
J 0
(-3300 -1600);
DISPLAY 1.170213 (-3300 -1600);
PAINT GREEN (-3300 -1600);
DISPLAY INVISIBLE (-3300 -1600);
FORCEPROP 1 LAST OFFPAGE TRUE
J 0
(-3100 -1625);
DISPLAY 0.872340 (-3100 -1625);
DISPLAY INVISIBLE (-3100 -1625);
FORCEADD Q_RES..1
(-2225 -1000);
FORCEPROP 1 LAST PART_NUMBER CS03322FB03
J 0
(-2375 -925);
DISPLAY 0.638298 (-2375 -925);
DISPLAY INVISIBLE (-2375 -925);
FORCEPROP 1 LAST MATERIAL CHIP
J 0
(-1950 -1000);
DISPLAY 0.638298 (-1950 -1000);
FORCEPROP 1 LAST VALUE 33.2
J 2
(-1975 -1000);
DISPLAY 0.638298 (-1975 -1000);
FORCEPROP 1 LAST LOCATION R3483
J 0
(-2475 -1000);
DISPLAY 0.638298 (-2475 -1000);
FORCEPROP 1 LASTPIN (-2325 -1000) $PN 1
J 0
(-2313 -988);
DISPLAY 0.787234 (-2313 -988);
PAINT MONO (-2313 -988);
FORCEPROP 1 LASTPIN (-2125 -1000) $PN 2
J 0
(-2163 -988);
DISPLAY 0.787234 (-2163 -988);
PAINT MONO (-2163 -988);
FORCEPROP 1 LAST PATH I20
J 0
(-2275 -850);
DISPLAY 0.978723 (-2275 -850);
PAINT WHITE (-2275 -850);
DISPLAY INVISIBLE (-2275 -850);
FORCEPROP 2 LAST CDS_LIB pure_quanta
J 0
(-2225 -1000);
DISPLAY INVISIBLE (-2225 -1000);
FORCEPROP 1 LAST WATTAGE 1/16W
J 2
(-2025 -875);
DISPLAY 0.638298 (-2025 -875);
DISPLAY INVISIBLE (-2025 -875);
FORCEPROP 1 LAST PACK_TYPE 0402LF
J 0
(-2375 -875);
DISPLAY 0.638298 (-2375 -875);
DISPLAY INVISIBLE (-2375 -875);
FORCEPROP 1 LAST TOLERANCE 1%
J 0
(-1950 -1000);
DISPLAY 0.638298 (-1950 -1000);
DISPLAY INVISIBLE (-1950 -1000);
FORCEPROP 0 LAST $SEC 1
J 0
(-1950 -950);
DISPLAY 0.680851 (-1950 -950);
PAINT MONO (-1950 -950);
DISPLAY INVISIBLE (-1950 -950);
FORCEPROP 0 LAST CDS_SEC 1
J 0
(-1950 -950);
DISPLAY 1.021277 (-1950 -950);
DISPLAY INVISIBLE (-1950 -950);
FORCEADD Q_RES..1
(-2225 -625);
FORCEPROP 1 LAST PART_NUMBER CS03322FB03
J 0
(-2375 -550);
DISPLAY 0.638298 (-2375 -550);
DISPLAY INVISIBLE (-2375 -550);
FORCEPROP 1 LAST VALUE 33.2
J 2
(-1975 -625);
DISPLAY 0.638298 (-1975 -625);
FORCEPROP 1 LAST MATERIAL CHIP
J 0
(-1950 -625);
DISPLAY 0.638298 (-1950 -625);
FORCEPROP 1 LAST LOCATION R3480
J 0
(-2475 -625);
DISPLAY 0.638298 (-2475 -625);
FORCEPROP 1 LASTPIN (-2325 -625) $PN 1
J 0
(-2313 -613);
DISPLAY 0.787234 (-2313 -613);
PAINT MONO (-2313 -613);
FORCEPROP 1 LASTPIN (-2125 -625) $PN 2
J 0
(-2163 -613);
DISPLAY 0.787234 (-2163 -613);
PAINT MONO (-2163 -613);
FORCEPROP 1 LAST PATH I21
J 0
(-2275 -475);
DISPLAY 0.978723 (-2275 -475);
PAINT WHITE (-2275 -475);
DISPLAY INVISIBLE (-2275 -475);
FORCEPROP 2 LAST CDS_LIB pure_quanta
J 0
(-2225 -625);
DISPLAY INVISIBLE (-2225 -625);
FORCEPROP 1 LAST WATTAGE 1/16W
J 2
(-2025 -500);
DISPLAY 0.638298 (-2025 -500);
DISPLAY INVISIBLE (-2025 -500);
FORCEPROP 1 LAST PACK_TYPE 0402LF
J 0
(-2375 -500);
DISPLAY 0.638298 (-2375 -500);
DISPLAY INVISIBLE (-2375 -500);
FORCEPROP 1 LAST TOLERANCE 1%
J 0
(-1950 -625);
DISPLAY 0.638298 (-1950 -625);
DISPLAY INVISIBLE (-1950 -625);
FORCEPROP 0 LAST $SEC 1
J 0
(-1950 -575);
DISPLAY 0.680851 (-1950 -575);
PAINT MONO (-1950 -575);
DISPLAY INVISIBLE (-1950 -575);
FORCEPROP 0 LAST CDS_SEC 1
J 0
(-1950 -575);
DISPLAY 1.021277 (-1950 -575);
DISPLAY INVISIBLE (-1950 -575);
FORCEADD Q_RES..1
(-2225 -750);
FORCEPROP 1 LAST PART_NUMBER CS03322FB03
J 0
(-2375 -675);
DISPLAY 0.638298 (-2375 -675);
DISPLAY INVISIBLE (-2375 -675);
FORCEPROP 1 LAST MATERIAL CHIP
J 0
(-1950 -750);
DISPLAY 0.638298 (-1950 -750);
FORCEPROP 1 LAST VALUE 33.2
J 2
(-1975 -750);
DISPLAY 0.638298 (-1975 -750);
FORCEPROP 1 LAST LOCATION R3481
J 0
(-2475 -750);
DISPLAY 0.638298 (-2475 -750);
FORCEPROP 1 LASTPIN (-2325 -750) $PN 1
J 0
(-2313 -738);
DISPLAY 0.787234 (-2313 -738);
PAINT MONO (-2313 -738);
FORCEPROP 1 LASTPIN (-2125 -750) $PN 2
J 0
(-2163 -738);
DISPLAY 0.787234 (-2163 -738);
PAINT MONO (-2163 -738);
FORCEPROP 1 LAST PATH I22
J 0
(-2275 -600);
DISPLAY 0.978723 (-2275 -600);
PAINT WHITE (-2275 -600);
DISPLAY INVISIBLE (-2275 -600);
FORCEPROP 2 LAST CDS_LIB pure_quanta
J 0
(-2225 -750);
DISPLAY INVISIBLE (-2225 -750);
FORCEPROP 1 LAST WATTAGE 1/16W
J 2
(-2025 -625);
DISPLAY 0.638298 (-2025 -625);
DISPLAY INVISIBLE (-2025 -625);
FORCEPROP 1 LAST PACK_TYPE 0402LF
J 0
(-2375 -625);
DISPLAY 0.638298 (-2375 -625);
DISPLAY INVISIBLE (-2375 -625);
FORCEPROP 1 LAST TOLERANCE 1%
J 0
(-1950 -750);
DISPLAY 0.638298 (-1950 -750);
DISPLAY INVISIBLE (-1950 -750);
FORCEPROP 0 LAST $SEC 1
J 0
(-1950 -700);
DISPLAY 0.680851 (-1950 -700);
PAINT MONO (-1950 -700);
DISPLAY INVISIBLE (-1950 -700);
FORCEPROP 0 LAST CDS_SEC 1
J 0
(-1950 -700);
DISPLAY 1.021277 (-1950 -700);
DISPLAY INVISIBLE (-1950 -700);
FORCEADD Q_RES..1
(-2225 -375);
FORCEPROP 1 LAST PART_NUMBER CS03322FB03
J 0
(-2375 -300);
DISPLAY 0.638298 (-2375 -300);
DISPLAY INVISIBLE (-2375 -300);
FORCEPROP 1 LAST VALUE 33.2
J 2
(-1975 -375);
DISPLAY 0.638298 (-1975 -375);
FORCEPROP 1 LAST MATERIAL CHIP
J 0
(-1950 -375);
DISPLAY 0.638298 (-1950 -375);
FORCEPROP 1 LAST LOCATION R3478
J 0
(-2475 -375);
DISPLAY 0.638298 (-2475 -375);
FORCEPROP 1 LASTPIN (-2325 -375) $PN 1
J 0
(-2313 -363);
DISPLAY 0.787234 (-2313 -363);
PAINT MONO (-2313 -363);
FORCEPROP 1 LASTPIN (-2125 -375) $PN 2
J 0
(-2163 -363);
DISPLAY 0.787234 (-2163 -363);
PAINT MONO (-2163 -363);
FORCEPROP 1 LAST PATH I23
J 0
(-2275 -225);
DISPLAY 0.978723 (-2275 -225);
PAINT WHITE (-2275 -225);
DISPLAY INVISIBLE (-2275 -225);
FORCEPROP 1 LAST TOLERANCE 1%
J 0
(-1950 -375);
DISPLAY 0.638298 (-1950 -375);
DISPLAY INVISIBLE (-1950 -375);
FORCEPROP 1 LAST PACK_TYPE 0402LF
J 0
(-2375 -250);
DISPLAY 0.638298 (-2375 -250);
DISPLAY INVISIBLE (-2375 -250);
FORCEPROP 1 LAST WATTAGE 1/16W
J 2
(-2025 -250);
DISPLAY 0.638298 (-2025 -250);
DISPLAY INVISIBLE (-2025 -250);
FORCEPROP 2 LAST CDS_LIB pure_quanta
J 0
(-2225 -375);
DISPLAY INVISIBLE (-2225 -375);
FORCEPROP 0 LAST $SEC 1
J 0
(-1950 -325);
DISPLAY 0.680851 (-1950 -325);
PAINT MONO (-1950 -325);
DISPLAY INVISIBLE (-1950 -325);
FORCEPROP 0 LAST CDS_SEC 1
J 0
(-1950 -325);
DISPLAY 1.021277 (-1950 -325);
DISPLAY INVISIBLE (-1950 -325);
FORCEADD Q_RES..1
(-2225 -500);
FORCEPROP 1 LAST PART_NUMBER CS03322FB03
J 0
(-2375 -425);
DISPLAY 0.638298 (-2375 -425);
DISPLAY INVISIBLE (-2375 -425);
FORCEPROP 1 LAST MATERIAL CHIP
J 0
(-1950 -500);
DISPLAY 0.638298 (-1950 -500);
FORCEPROP 1 LAST VALUE 33.2
J 2
(-1975 -500);
DISPLAY 0.638298 (-1975 -500);
FORCEPROP 1 LAST LOCATION R3479
J 0
(-2475 -500);
DISPLAY 0.638298 (-2475 -500);
FORCEPROP 1 LASTPIN (-2325 -500) $PN 1
J 0
(-2313 -488);
DISPLAY 0.787234 (-2313 -488);
PAINT MONO (-2313 -488);
FORCEPROP 1 LASTPIN (-2125 -500) $PN 2
J 0
(-2163 -488);
DISPLAY 0.787234 (-2163 -488);
PAINT MONO (-2163 -488);
FORCEPROP 1 LAST PATH I24
J 0
(-2275 -350);
DISPLAY 0.978723 (-2275 -350);
PAINT WHITE (-2275 -350);
DISPLAY INVISIBLE (-2275 -350);
FORCEPROP 2 LAST CDS_LIB pure_quanta
J 0
(-2225 -500);
DISPLAY INVISIBLE (-2225 -500);
FORCEPROP 1 LAST WATTAGE 1/16W
J 2
(-2025 -375);
DISPLAY 0.638298 (-2025 -375);
DISPLAY INVISIBLE (-2025 -375);
FORCEPROP 1 LAST PACK_TYPE 0402LF
J 0
(-2375 -375);
DISPLAY 0.638298 (-2375 -375);
DISPLAY INVISIBLE (-2375 -375);
FORCEPROP 1 LAST TOLERANCE 1%
J 0
(-1950 -500);
DISPLAY 0.638298 (-1950 -500);
DISPLAY INVISIBLE (-1950 -500);
FORCEPROP 0 LAST $SEC 1
J 0
(-1950 -450);
DISPLAY 0.680851 (-1950 -450);
PAINT MONO (-1950 -450);
DISPLAY INVISIBLE (-1950 -450);
FORCEPROP 0 LAST CDS_SEC 1
J 0
(-1950 -450);
DISPLAY 1.021277 (-1950 -450);
DISPLAY INVISIBLE (-1950 -450);
FORCEADD Q_RES..1
(-2225 -125);
FORCEPROP 1 LAST PART_NUMBER CS03322FB03
J 0
(-2375 -50);
DISPLAY 0.638298 (-2375 -50);
DISPLAY INVISIBLE (-2375 -50);
FORCEPROP 1 LAST VALUE 33.2
J 2
(-1975 -125);
DISPLAY 0.638298 (-1975 -125);
FORCEPROP 1 LAST MATERIAL CHIP
J 0
(-1950 -125);
DISPLAY 0.638298 (-1950 -125);
FORCEPROP 1 LAST LOCATION R3476
J 0
(-2475 -125);
DISPLAY 0.638298 (-2475 -125);
FORCEPROP 1 LASTPIN (-2325 -125) $PN 1
J 0
(-2313 -113);
DISPLAY 0.787234 (-2313 -113);
PAINT MONO (-2313 -113);
FORCEPROP 1 LASTPIN (-2125 -125) $PN 2
J 0
(-2163 -113);
DISPLAY 0.787234 (-2163 -113);
PAINT MONO (-2163 -113);
FORCEPROP 2 LAST CDS_LIB pure_quanta
J 0
(-2225 -125);
DISPLAY INVISIBLE (-2225 -125);
FORCEPROP 1 LAST PATH I25
J 0
(-2275 25);
DISPLAY 0.978723 (-2275 25);
PAINT WHITE (-2275 25);
DISPLAY INVISIBLE (-2275 25);
FORCEPROP 1 LAST WATTAGE 1/16W
J 2
(-2025 0);
DISPLAY 0.638298 (-2025 0);
DISPLAY INVISIBLE (-2025 0);
FORCEPROP 1 LAST PACK_TYPE 0402LF
J 0
(-2375 0);
DISPLAY 0.638298 (-2375 0);
DISPLAY INVISIBLE (-2375 0);
FORCEPROP 1 LAST TOLERANCE 1%
J 0
(-1950 -125);
DISPLAY 0.638298 (-1950 -125);
DISPLAY INVISIBLE (-1950 -125);
FORCEPROP 0 LAST $SEC 1
J 0
(-1950 -75);
DISPLAY 0.680851 (-1950 -75);
PAINT MONO (-1950 -75);
DISPLAY INVISIBLE (-1950 -75);
FORCEPROP 0 LAST CDS_SEC 1
J 0
(-1950 -75);
DISPLAY 1.021277 (-1950 -75);
DISPLAY INVISIBLE (-1950 -75);
FORCEADD Q_RES..1
(-2225 -250);
FORCEPROP 1 LAST PART_NUMBER CS03322FB03
J 0
(-2375 -175);
DISPLAY 0.638298 (-2375 -175);
DISPLAY INVISIBLE (-2375 -175);
FORCEPROP 1 LAST VALUE 33.2
J 2
(-1975 -250);
DISPLAY 0.638298 (-1975 -250);
FORCEPROP 1 LAST MATERIAL CHIP
J 0
(-1950 -250);
DISPLAY 0.638298 (-1950 -250);
FORCEPROP 1 LAST LOCATION R3477
J 0
(-2475 -250);
DISPLAY 0.638298 (-2475 -250);
FORCEPROP 1 LASTPIN (-2325 -250) $PN 1
J 0
(-2313 -238);
DISPLAY 0.787234 (-2313 -238);
PAINT MONO (-2313 -238);
FORCEPROP 1 LASTPIN (-2125 -250) $PN 2
J 0
(-2163 -238);
DISPLAY 0.787234 (-2163 -238);
PAINT MONO (-2163 -238);
FORCEPROP 1 LAST PATH I26
J 0
(-2275 -100);
DISPLAY 0.978723 (-2275 -100);
PAINT WHITE (-2275 -100);
DISPLAY INVISIBLE (-2275 -100);
FORCEPROP 2 LAST CDS_LIB pure_quanta
J 0
(-2225 -250);
DISPLAY INVISIBLE (-2225 -250);
FORCEPROP 1 LAST WATTAGE 1/16W
J 2
(-2025 -125);
DISPLAY 0.638298 (-2025 -125);
DISPLAY INVISIBLE (-2025 -125);
FORCEPROP 1 LAST PACK_TYPE 0402LF
J 0
(-2375 -125);
DISPLAY 0.638298 (-2375 -125);
DISPLAY INVISIBLE (-2375 -125);
FORCEPROP 1 LAST TOLERANCE 1%
J 0
(-1950 -250);
DISPLAY 0.638298 (-1950 -250);
DISPLAY INVISIBLE (-1950 -250);
FORCEPROP 0 LAST $SEC 1
J 0
(-1950 -200);
DISPLAY 0.680851 (-1950 -200);
PAINT MONO (-1950 -200);
DISPLAY INVISIBLE (-1950 -200);
FORCEPROP 0 LAST CDS_SEC 1
J 0
(-1950 -200);
DISPLAY 1.021277 (-1950 -200);
DISPLAY INVISIBLE (-1950 -200);
FORCEADD OFFPAGE..2
(-775 -1675);
FORCEPROP 2 LAST $XR0 240 
J 0
(-586 -1675);
DISPLAY 0.638298 (-586 -1675);
PAINT MONO (-586 -1675);
FORCEPROP 2 LAST PATH I27
J 0
(-575 -1625);
DISPLAY 1.021277 (-575 -1625);
DISPLAY INVISIBLE (-575 -1625);
FORCEPROP 2 LAST CDS_LIB standard
J 0
(-775 -1675);
PAINT MONO (-775 -1675);
DISPLAY INVISIBLE (-775 -1675);
FORCEPROP 1 LAST OFFPAGE TRUE
J 0
(-450 -1800);
DISPLAY 0.872340 (-450 -1800);
PAINT GREEN (-450 -1800);
DISPLAY INVISIBLE (-450 -1800);
FORCEPROP 1 LAST COMMENT_BODY TRUE
J 0
(-820 -1770);
DISPLAY 0.872340 (-820 -1770);
PAINT PEACH (-820 -1770);
DISPLAY INVISIBLE (-820 -1770);
FORCEADD OFFPAGE..2
(-800 -1500);
FORCEPROP 2 LAST $XR0 213 
J 0
(-611 -1500);
DISPLAY 0.638298 (-611 -1500);
PAINT MONO (-611 -1500);
FORCEPROP 2 LAST PATH I28
J 0
(-600 -1450);
DISPLAY 1.021277 (-600 -1450);
DISPLAY INVISIBLE (-600 -1450);
FORCEPROP 2 LAST CDS_LIB standard
J 0
(-800 -1500);
DISPLAY INVISIBLE (-800 -1500);
FORCEPROP 1 LAST COMMENT_BODY TRUE
J 0
(-845 -1595);
DISPLAY 1.170213 (-845 -1595);
PAINT GREEN (-845 -1595);
DISPLAY INVISIBLE (-845 -1595);
FORCEPROP 1 LAST OFFPAGE TRUE
J 0
(-475 -1625);
DISPLAY 1.170213 (-475 -1625);
PAINT GREEN (-475 -1625);
DISPLAY INVISIBLE (-475 -1625);
FORCEADD OFFPAGE..2
(-800 -1375);
FORCEPROP 2 LAST $XR0 213 
J 0
(-611 -1375);
DISPLAY 0.638298 (-611 -1375);
PAINT MONO (-611 -1375);
FORCEPROP 2 LAST PATH I29
J 0
(-600 -1325);
DISPLAY 1.021277 (-600 -1325);
DISPLAY INVISIBLE (-600 -1325);
FORCEPROP 1 LAST OFFPAGE TRUE
J 0
(-475 -1500);
DISPLAY 1.170213 (-475 -1500);
PAINT GREEN (-475 -1500);
DISPLAY INVISIBLE (-475 -1500);
FORCEPROP 1 LAST COMMENT_BODY TRUE
J 0
(-845 -1470);
DISPLAY 1.170213 (-845 -1470);
PAINT GREEN (-845 -1470);
DISPLAY INVISIBLE (-845 -1470);
FORCEPROP 2 LAST CDS_LIB standard
J 0
(-800 -1375);
DISPLAY INVISIBLE (-800 -1375);
FORCEADD OFFPAGE..1
(-3425 -1375);
FORCEPROP 2 LAST $XR1 227 
J 0
(-3797 -1375);
DISPLAY 0.638298 (-3797 -1375);
PAINT MONO (-3797 -1375);
FORCEPROP 2 LAST $XR0 147 
J 0
(-3677 -1375);
DISPLAY 0.638298 (-3677 -1375);
PAINT MONO (-3677 -1375);
FORCEPROP 2 LAST PATH I3
J 0
(-3675 -1325);
DISPLAY 1.021277 (-3675 -1325);
DISPLAY INVISIBLE (-3675 -1325);
FORCEPROP 1 LAST OFFPAGE TRUE
J 0
(-3100 -1500);
DISPLAY 0.872340 (-3100 -1500);
DISPLAY INVISIBLE (-3100 -1500);
FORCEPROP 1 LAST COMMENT_BODY TRUE
J 0
(-3300 -1475);
DISPLAY 1.170213 (-3300 -1475);
PAINT GREEN (-3300 -1475);
DISPLAY INVISIBLE (-3300 -1475);
FORCEPROP 2 LAST CDS_LIB standard
J 0
(-3425 -1375);
DISPLAY INVISIBLE (-3425 -1375);
FORCEADD OFFPAGE..1
R 2
(-800 -1250);
FORCEPROP 2 LAST $XR0 213 
J 0
(-614 -1250);
DISPLAY 0.638298 (-614 -1250);
PAINT MONO (-614 -1250);
FORCEPROP 2 LAST PATH I30
J 0
(-600 -1200);
DISPLAY 1.021277 (-600 -1200);
DISPLAY INVISIBLE (-600 -1200);
FORCEPROP 1 LAST COMMENT_BODY TRUE
J 2
(-925 -1350);
DISPLAY 1.170213 (-925 -1350);
PAINT GREEN (-925 -1350);
DISPLAY INVISIBLE (-925 -1350);
FORCEPROP 1 LAST OFFPAGE TRUE
J 2
(-1125 -1375);
DISPLAY 0.872340 (-1125 -1375);
DISPLAY INVISIBLE (-1125 -1375);
FORCEPROP 2 LAST CDS_LIB standard
J 0
(-800 -1250);
DISPLAY INVISIBLE (-800 -1250);
FORCEADD OFFPAGE..2
(-800 -1125);
FORCEPROP 2 LAST $XR0 213 
J 0
(-611 -1125);
DISPLAY 0.638298 (-611 -1125);
PAINT MONO (-611 -1125);
FORCEPROP 2 LAST PATH I31
J 0
(-600 -1075);
DISPLAY 1.021277 (-600 -1075);
DISPLAY INVISIBLE (-600 -1075);
FORCEPROP 2 LAST CDS_LIB standard
J 0
(-800 -1125);
DISPLAY INVISIBLE (-800 -1125);
FORCEPROP 1 LAST COMMENT_BODY TRUE
J 0
(-845 -1220);
DISPLAY 1.170213 (-845 -1220);
PAINT GREEN (-845 -1220);
DISPLAY INVISIBLE (-845 -1220);
FORCEPROP 1 LAST OFFPAGE TRUE
J 0
(-475 -1250);
DISPLAY 1.170213 (-475 -1250);
PAINT GREEN (-475 -1250);
DISPLAY INVISIBLE (-475 -1250);
FORCEADD OFFPAGE..1
R 2
(-800 -1000);
FORCEPROP 2 LAST $XR0 213 
J 0
(-614 -1000);
DISPLAY 0.638298 (-614 -1000);
PAINT MONO (-614 -1000);
FORCEPROP 2 LAST PATH I32
J 0
(-600 -950);
DISPLAY 1.021277 (-600 -950);
DISPLAY INVISIBLE (-600 -950);
FORCEPROP 1 LAST COMMENT_BODY TRUE
J 2
(-925 -1100);
DISPLAY 1.170213 (-925 -1100);
PAINT GREEN (-925 -1100);
DISPLAY INVISIBLE (-925 -1100);
FORCEPROP 1 LAST OFFPAGE TRUE
J 2
(-1125 -1125);
DISPLAY 0.872340 (-1125 -1125);
DISPLAY INVISIBLE (-1125 -1125);
FORCEPROP 2 LAST CDS_LIB standard
J 0
(-800 -1000);
DISPLAY INVISIBLE (-800 -1000);
FORCEADD OFFPAGE..1
R 2
(-800 -875);
FORCEPROP 2 LAST $XR0 213 
J 0
(-614 -875);
DISPLAY 0.638298 (-614 -875);
PAINT MONO (-614 -875);
FORCEPROP 2 LAST PATH I33
J 0
(-600 -825);
DISPLAY 1.021277 (-600 -825);
DISPLAY INVISIBLE (-600 -825);
FORCEPROP 1 LAST COMMENT_BODY TRUE
J 2
(-925 -975);
DISPLAY 1.170213 (-925 -975);
PAINT GREEN (-925 -975);
DISPLAY INVISIBLE (-925 -975);
FORCEPROP 1 LAST OFFPAGE TRUE
J 2
(-1125 -1000);
DISPLAY 0.872340 (-1125 -1000);
DISPLAY INVISIBLE (-1125 -1000);
FORCEPROP 2 LAST CDS_LIB standard
J 0
(-800 -875);
DISPLAY INVISIBLE (-800 -875);
FORCEADD OFFPAGE..2
(-800 -750);
FORCEPROP 2 LAST $XR0 213 
J 0
(-611 -750);
DISPLAY 0.638298 (-611 -750);
PAINT MONO (-611 -750);
FORCEPROP 2 LAST PATH I34
J 0
(-600 -700);
DISPLAY 1.021277 (-600 -700);
DISPLAY INVISIBLE (-600 -700);
FORCEPROP 2 LAST CDS_LIB standard
J 0
(-800 -750);
DISPLAY INVISIBLE (-800 -750);
FORCEPROP 1 LAST COMMENT_BODY TRUE
J 0
(-845 -845);
DISPLAY 1.170213 (-845 -845);
PAINT GREEN (-845 -845);
DISPLAY INVISIBLE (-845 -845);
FORCEPROP 1 LAST OFFPAGE TRUE
J 0
(-475 -875);
DISPLAY 1.170213 (-475 -875);
PAINT GREEN (-475 -875);
DISPLAY INVISIBLE (-475 -875);
FORCEADD OFFPAGE..2
(-800 -625);
FORCEPROP 2 LAST $XR0 213 
J 0
(-611 -625);
DISPLAY 0.638298 (-611 -625);
PAINT MONO (-611 -625);
FORCEPROP 2 LAST PATH I35
J 0
(-600 -575);
DISPLAY 1.021277 (-600 -575);
DISPLAY INVISIBLE (-600 -575);
FORCEPROP 2 LAST CDS_LIB standard
J 0
(-800 -625);
DISPLAY INVISIBLE (-800 -625);
FORCEPROP 1 LAST COMMENT_BODY TRUE
J 0
(-845 -720);
DISPLAY 1.170213 (-845 -720);
PAINT GREEN (-845 -720);
DISPLAY INVISIBLE (-845 -720);
FORCEPROP 1 LAST OFFPAGE TRUE
J 0
(-475 -750);
DISPLAY 1.170213 (-475 -750);
PAINT GREEN (-475 -750);
DISPLAY INVISIBLE (-475 -750);
FORCEADD OFFPAGE..1
R 2
(-800 -500);
FORCEPROP 2 LAST $XR0 213 
J 0
(-614 -500);
DISPLAY 0.638298 (-614 -500);
PAINT MONO (-614 -500);
FORCEPROP 2 LAST PATH I36
J 0
(-600 -450);
DISPLAY 1.021277 (-600 -450);
DISPLAY INVISIBLE (-600 -450);
FORCEPROP 1 LAST COMMENT_BODY TRUE
J 2
(-925 -600);
DISPLAY 1.170213 (-925 -600);
PAINT GREEN (-925 -600);
DISPLAY INVISIBLE (-925 -600);
FORCEPROP 1 LAST OFFPAGE TRUE
J 2
(-1125 -625);
DISPLAY 0.872340 (-1125 -625);
DISPLAY INVISIBLE (-1125 -625);
FORCEPROP 2 LAST CDS_LIB standard
J 0
(-800 -500);
DISPLAY INVISIBLE (-800 -500);
FORCEADD OFFPAGE..1
R 2
(-800 -375);
FORCEPROP 2 LAST $XR0 213 
J 0
(-614 -375);
DISPLAY 0.638298 (-614 -375);
PAINT MONO (-614 -375);
FORCEPROP 2 LAST PATH I37
J 0
(-600 -325);
DISPLAY 1.021277 (-600 -325);
DISPLAY INVISIBLE (-600 -325);
FORCEPROP 1 LAST OFFPAGE TRUE
J 2
(-1125 -500);
DISPLAY 0.872340 (-1125 -500);
DISPLAY INVISIBLE (-1125 -500);
FORCEPROP 1 LAST COMMENT_BODY TRUE
J 2
(-925 -475);
DISPLAY 1.170213 (-925 -475);
PAINT GREEN (-925 -475);
DISPLAY INVISIBLE (-925 -475);
FORCEPROP 2 LAST CDS_LIB standard
J 0
(-800 -375);
DISPLAY INVISIBLE (-800 -375);
FORCEADD OFFPAGE..1
R 2
(-800 -250);
FORCEPROP 2 LAST $XR0 213 
J 0
(-614 -250);
DISPLAY 0.638298 (-614 -250);
PAINT MONO (-614 -250);
FORCEPROP 2 LAST PATH I38
J 0
(-600 -200);
DISPLAY 1.021277 (-600 -200);
DISPLAY INVISIBLE (-600 -200);
FORCEPROP 2 LAST CDS_LIB standard
J 2
(-800 -250);
DISPLAY INVISIBLE (-800 -250);
FORCEPROP 1 LAST COMMENT_BODY TRUE
J 2
(-925 -350);
DISPLAY 1.170213 (-925 -350);
PAINT GREEN (-925 -350);
DISPLAY INVISIBLE (-925 -350);
FORCEPROP 1 LAST OFFPAGE TRUE
J 2
(-1125 -375);
DISPLAY 0.872340 (-1125 -375);
DISPLAY INVISIBLE (-1125 -375);
FORCEADD OFFPAGE..2
(-800 -125);
FORCEPROP 2 LAST $XR0 213 
J 0
(-611 -125);
DISPLAY 0.638298 (-611 -125);
PAINT MONO (-611 -125);
FORCEPROP 2 LAST PATH I39
J 0
(-600 -75);
DISPLAY 1.021277 (-600 -75);
DISPLAY INVISIBLE (-600 -75);
FORCEPROP 2 LAST CDS_LIB standard
J 0
(-800 -125);
DISPLAY INVISIBLE (-800 -125);
FORCEPROP 1 LAST OFFPAGE TRUE
J 0
(-475 -250);
DISPLAY 1.170213 (-475 -250);
PAINT GREEN (-475 -250);
DISPLAY INVISIBLE (-475 -250);
FORCEPROP 1 LAST COMMENT_BODY TRUE
J 0
(-845 -220);
DISPLAY 1.170213 (-845 -220);
PAINT GREEN (-845 -220);
DISPLAY INVISIBLE (-845 -220);
FORCEADD OFFPAGE..1
(-3425 -1125);
FORCEPROP 2 LAST $XR0 147 
J 0
(-3677 -1125);
DISPLAY 0.638298 (-3677 -1125);
PAINT MONO (-3677 -1125);
FORCEPROP 2 LAST PATH I4
J 0
(-3675 -1075);
DISPLAY 1.021277 (-3675 -1075);
DISPLAY INVISIBLE (-3675 -1075);
FORCEPROP 2 LAST CDS_LIB standard
J 0
(-3425 -1125);
DISPLAY INVISIBLE (-3425 -1125);
FORCEPROP 1 LAST COMMENT_BODY TRUE
J 0
(-3300 -1225);
DISPLAY 1.170213 (-3300 -1225);
PAINT GREEN (-3300 -1225);
DISPLAY INVISIBLE (-3300 -1225);
FORCEPROP 1 LAST OFFPAGE TRUE
J 0
(-3100 -1250);
DISPLAY 0.872340 (-3100 -1250);
DISPLAY INVISIBLE (-3100 -1250);
FORCEADD OFFPAGE..1
(-3500 475);
FORCEPROP 2 LAST $XR0 258 
J 0
(-3752 475);
DISPLAY 0.638298 (-3752 475);
PAINT MONO (-3752 475);
FORCEPROP 2 LAST CDS_LIB standard
J 0
(-3500 475);
DISPLAY INVISIBLE (-3500 475);
FORCEPROP 1 LAST OFFPAGE TRUE
J 0
(-3175 350);
DISPLAY 0.872340 (-3175 350);
DISPLAY INVISIBLE (-3175 350);
FORCEPROP 1 LAST COMMENT_BODY TRUE
J 0
(-3375 375);
DISPLAY 1.170213 (-3375 375);
PAINT GREEN (-3375 375);
DISPLAY INVISIBLE (-3375 375);
FORCEPROP 2 LAST PATH I40
J 0
(-3775 525);
DISPLAY 1.021277 (-3775 525);
DISPLAY INVISIBLE (-3775 525);
FORCEADD Q_RES..2
(-3375 850);
FORCEPROP 1 LAST PART_NUMBER CS31002FB08
J 0
(-3335 725);
DISPLAY 0.638298 (-3335 725);
DISPLAY INVISIBLE (-3335 725);
FORCEPROP 1 LAST VALUE 10K
J 0
(-3330 925);
DISPLAY 0.638298 (-3330 925);
FORCEPROP 1 LAST MATERIAL EMPTY
J 0
(-3335 775);
DISPLAY 0.638298 (-3335 775);
PAINT RED (-3335 775);
FORCEPROP 1 LAST WATTAGE 1/16W
J 0
(-3335 825);
DISPLAY 0.638298 (-3335 825);
FORCEPROP 1 LAST TOLERANCE 1%
J 0
(-3330 875);
DISPLAY 0.638298 (-3330 875);
FORCEPROP 1 LAST PACK_TYPE 0402LF
J 0
(-3335 675);
DISPLAY 0.638298 (-3335 675);
FORCEPROP 1 LAST $LOCATION R2343
J 0
(-3330 975);
DISPLAY 0.978723 (-3330 975);
FORCEPROP 1 LASTPIN (-3375 950) $PN 1
J 0
(-3370 912);
DISPLAY 0.787234 (-3370 912);
PAINT MONO (-3370 912);
FORCEPROP 1 LASTPIN (-3375 750) $PN 2
J 0
(-3370 760);
DISPLAY 0.787234 (-3370 760);
PAINT MONO (-3370 760);
FORCEPROP 2 LAST CDS_LIB pure_quanta
J 0
(-3375 850);
DISPLAY INVISIBLE (-3375 850);
FORCEPROP 1 LAST PATH I41
J 0
(-3325 1025);
DISPLAY 0.978723 (-3325 1025);
PAINT WHITE (-3325 1025);
DISPLAY INVISIBLE (-3325 1025);
FORCEPROP 0 LAST CDS_LOCATION R2343
J 0
(-3325 1025);
DISPLAY 1.021277 (-3325 1025);
DISPLAY INVISIBLE (-3325 1025);
FORCEPROP 0 LAST $SEC 1
J 0
(-3325 1025);
DISPLAY 0.680851 (-3325 1025);
PAINT MONO (-3325 1025);
DISPLAY INVISIBLE (-3325 1025);
FORCEPROP 0 LAST CDS_SEC 1
J 0
(-3325 1025);
DISPLAY 1.021277 (-3325 1025);
DISPLAY INVISIBLE (-3325 1025);
FORCEADD UNIVERSAL_POWER..1
(-3375 1100);
FORCEPROP 3 LASTPIN (-3375 1050) SIG_NAME P5V_AUX_VCC\g
J 0
(-3365 1060);
DISPLAY 0.659574 (-3365 1060);
PAINT MONO (-3365 1060);
DISPLAY INVISIBLE (-3365 1060);
FORCEPROP 1 LAST HDL_POWER P5V_AUX_VCC
J 1
(-3375 1150);
DISPLAY 0.872340 (-3375 1150);
PAINT GREEN (-3375 1150);
FORCEPROP 2 LAST CDS_LIB logical_power
J 0
(-3375 1100);
DISPLAY INVISIBLE (-3375 1100);
FORCEPROP 1 LAST PATH I42
J 0
(-3325 1125);
DISPLAY 0.872340 (-3325 1125);
PAINT AQUA (-3325 1125);
DISPLAY INVISIBLE (-3325 1125);
FORCEADD MOSFET_NCH_DUAL..1
(-2450 525);
FORCEPROP 1 LAST PART_NUMBER BAM138K0003
J 0
(-2299 439);
DISPLAY 0.723404 (-2299 439);
PAINT GREEN (-2299 439);
DISPLAY INVISIBLE (-2299 439);
FORCEPROP 1 LAST MATERIAL IC
J 0
(-2299 374);
DISPLAY 0.723404 (-2299 374);
PAINT GREEN (-2299 374);
FORCEPROP 2 LAST PART_TYPE SMLF
J 0
(-2275 600);
DISPLAY 1.021277 (-2275 600);
FORCEPROP 2 LAST VALUE PJT138K
J 0
(-2275 550);
DISPLAY 1.021277 (-2275 550);
FORCEPROP 1 LAST LOCATION Q50
J 0
(-2299 499);
DISPLAY 0.723404 (-2299 499);
PAINT GREEN (-2299 499);
FORCEPROP 0 LASTPIN (-2400 725) $PN 6
R 1
J 0
(-2410 735);
DISPLAY 0.680851 (-2410 735);
PAINT MONO (-2410 735);
FORCEPROP 0 LASTPIN (-2650 475) $PN 2
J 2
(-2660 485);
DISPLAY 0.680851 (-2660 485);
PAINT MONO (-2660 485);
FORCEPROP 0 LASTPIN (-2400 325) $PN 1
R 1
J 2
(-2410 315);
DISPLAY 0.680851 (-2410 315);
PAINT MONO (-2410 315);
FORCEPROP 2 LAST CDS_LIB pure_quanta
J 0
(-2450 525);
DISPLAY INVISIBLE (-2450 525);
FORCEPROP 1 LAST CDS_LMAN_SYM_OUTLINE -150,150,150,-150
J 0
(-2450 525);
DISPLAY 0.468085 (-2450 525);
PAINT GREEN (-2450 525);
DISPLAY INVISIBLE (-2450 525);
FORCEPROP 1 LAST NEEDS_NO_SIZE TRUE
J 0
(-2450 524);
DISPLAY 0.468085 (-2450 524);
PAINT GREEN (-2450 524);
DISPLAY INVISIBLE (-2450 524);
FORCEPROP 1 LAST PATH I43
J 0
(-2450 525);
DISPLAY 0.723404 (-2450 525);
PAINT GREEN (-2450 525);
DISPLAY INVISIBLE (-2450 525);
FORCEPROP 0 LAST $SEC 1
J 0
(-2275 650);
DISPLAY 0.680851 (-2275 650);
PAINT MONO (-2275 650);
DISPLAY INVISIBLE (-2275 650);
FORCEPROP 0 LAST CDS_SEC 1
J 0
(-2275 650);
DISPLAY 1.021277 (-2275 650);
DISPLAY INVISIBLE (-2275 650);
FORCEADD UNIVERSAL_GND..1
(-2400 225);
FORCEPROP 3 LASTPIN (-2400 275) SIG_NAME GND\g
J 0
(-2390 285);
DISPLAY 0.659574 (-2390 285);
PAINT MONO (-2390 285);
DISPLAY INVISIBLE (-2390 285);
FORCEPROP 2 LAST CDS_LIB logical_power
J 0
(-2400 225);
DISPLAY INVISIBLE (-2400 225);
FORCEPROP 1 LAST HDL_POWER GND
J 1
(-2375 150);
DISPLAY 0.872340 (-2375 150);
PAINT GREEN (-2375 150);
DISPLAY INVISIBLE (-2375 150);
FORCEPROP 1 LAST PATH I44
J 0
(-2325 225);
DISPLAY 0.872340 (-2325 225);
PAINT AQUA (-2325 225);
DISPLAY INVISIBLE (-2325 225);
FORCEADD Q_RES..2
(-2400 1050);
FORCEPROP 1 LAST PART_NUMBER CS24702JB10
J 0
(-2360 875);
DISPLAY 0.510638 (-2360 875);
DISPLAY INVISIBLE (-2360 875);
FORCEPROP 1 LAST PACK_TYPE 0402LF
J 0
(-2360 925);
DISPLAY 0.510638 (-2360 925);
FORCEPROP 1 LAST VALUE 4.7K
J 0
(-2355 1125);
DISPLAY 0.510638 (-2355 1125);
FORCEPROP 1 LAST MATERIAL CHIP
J 0
(-2360 975);
DISPLAY 0.510638 (-2360 975);
FORCEPROP 1 LAST WATTAGE 1/16W
J 0
(-2360 1025);
DISPLAY 0.510638 (-2360 1025);
FORCEPROP 1 LAST TOLERANCE 5%
J 0
(-2355 1075);
DISPLAY 0.510638 (-2355 1075);
FORCEPROP 1 LAST $LOCATION R2344
J 0
(-2355 1175);
DISPLAY 0.978723 (-2355 1175);
FORCEPROP 1 LASTPIN (-2400 1150) $PN 1
J 0
(-2395 1112);
DISPLAY 0.787234 (-2395 1112);
PAINT MONO (-2395 1112);
FORCEPROP 1 LASTPIN (-2400 950) $PN 2
J 0
(-2395 960);
DISPLAY 0.787234 (-2395 960);
PAINT MONO (-2395 960);
FORCEPROP 2 LAST CDS_LIB pure_quanta
J 0
(-2400 1050);
DISPLAY INVISIBLE (-2400 1050);
FORCEPROP 1 LAST PATH I45
J 0
(-2350 1225);
DISPLAY 0.978723 (-2350 1225);
PAINT WHITE (-2350 1225);
DISPLAY INVISIBLE (-2350 1225);
FORCEPROP 0 LAST CDS_LOCATION R2344
J 0
(-2350 1225);
DISPLAY 1.021277 (-2350 1225);
DISPLAY INVISIBLE (-2350 1225);
FORCEPROP 0 LAST $SEC 1
J 0
(-2350 1225);
DISPLAY 0.680851 (-2350 1225);
PAINT MONO (-2350 1225);
DISPLAY INVISIBLE (-2350 1225);
FORCEPROP 0 LAST CDS_SEC 1
J 0
(-2350 1225);
DISPLAY 1.021277 (-2350 1225);
DISPLAY INVISIBLE (-2350 1225);
FORCEADD UNIVERSAL_POWER..1
(-2400 1300);
FORCEPROP 3 LASTPIN (-2400 1250) SIG_NAME P3V3_AUX\g
J 0
(-2390 1260);
DISPLAY 0.659574 (-2390 1260);
PAINT MONO (-2390 1260);
DISPLAY INVISIBLE (-2390 1260);
FORCEPROP 1 LAST HDL_POWER P3V3_AUX
J 1
(-2400 1350);
DISPLAY 0.872340 (-2400 1350);
PAINT GREEN (-2400 1350);
FORCEPROP 2 LAST CDS_LIB logical_power
J 0
(-2400 1300);
PAINT MONO (-2400 1300);
DISPLAY INVISIBLE (-2400 1300);
FORCEPROP 1 LAST PATH I46
J 0
(-2350 1325);
DISPLAY 0.872340 (-2350 1325);
PAINT AQUA (-2350 1325);
DISPLAY INVISIBLE (-2350 1325);
FORCEADD Q_RES..2
R 2
(-2300 2625);
FORCEPROP 1 LAST PART_NUMBER CS31002FB08
J 2
(-2340 2500);
DISPLAY 0.638298 (-2340 2500);
DISPLAY INVISIBLE (-2340 2500);
FORCEPROP 1 LAST WATTAGE 1/16W
J 2
(-2340 2600);
DISPLAY 0.638298 (-2340 2600);
FORCEPROP 1 LAST PACK_TYPE 0402LF
J 2
(-2340 2450);
DISPLAY 0.638298 (-2340 2450);
FORCEPROP 1 LAST TOLERANCE 1%
J 2
(-2345 2650);
DISPLAY 0.638298 (-2345 2650);
FORCEPROP 1 LAST VALUE 10K
J 2
(-2345 2700);
DISPLAY 0.638298 (-2345 2700);
FORCEPROP 1 LAST MATERIAL CHIP
J 2
(-2340 2550);
DISPLAY 0.638298 (-2340 2550);
FORCEPROP 1 LAST $LOCATION R1681
J 2
(-2345 2750);
DISPLAY 0.638298 (-2345 2750);
FORCEPROP 1 LASTPIN (-2300 2725) $PN 1
J 2
(-2305 2687);
DISPLAY 0.787234 (-2305 2687);
FORCEPROP 1 LASTPIN (-2300 2525) $PN 2
J 2
(-2305 2535);
DISPLAY 0.787234 (-2305 2535);
FORCEPROP 1 LAST PATH I47
J 2
(-2350 2800);
DISPLAY 0.978723 (-2350 2800);
PAINT WHITE (-2350 2800);
DISPLAY INVISIBLE (-2350 2800);
FORCEPROP 2 LAST CDS_LIB pure_quanta
J 2
(-2300 2625);
PAINT MONO (-2300 2625);
DISPLAY INVISIBLE (-2300 2625);
FORCEPROP 2 LAST CDS_LOCATION R1681
J 0
(-2350 2850);
DISPLAY 1.021277 (-2350 2850);
DISPLAY INVISIBLE (-2350 2850);
FORCEPROP 2 LAST $SEC 1
J 0
(-2350 2850);
DISPLAY 0.680851 (-2350 2850);
PAINT MONO (-2350 2850);
DISPLAY INVISIBLE (-2350 2850);
FORCEPROP 2 LAST CDS_SEC 1
J 0
(-2350 2850);
DISPLAY 1.021277 (-2350 2850);
DISPLAY INVISIBLE (-2350 2850);
FORCEADD UNIVERSAL_POWER..1
(-2300 2900);
FORCEPROP 3 LASTPIN (-2300 2850) SIG_NAME P3V3_AUX\g
J 0
(-2290 2860);
DISPLAY 0.659574 (-2290 2860);
PAINT MONO (-2290 2860);
DISPLAY INVISIBLE (-2290 2860);
FORCEPROP 1 LAST HDL_POWER P3V3_AUX
J 1
(-2300 2950);
DISPLAY 0.872340 (-2300 2950);
PAINT GREEN (-2300 2950);
FORCEPROP 1 LAST PATH I48
J 0
(-2250 2925);
DISPLAY 0.872340 (-2250 2925);
PAINT AQUA (-2250 2925);
DISPLAY INVISIBLE (-2250 2925);
FORCEPROP 2 LAST CDS_LIB logical_power
J 0
(-2300 2900);
PAINT MONO (-2300 2900);
DISPLAY INVISIBLE (-2300 2900);
FORCEADD MOSFET_NCH_DUAL..2
(-1300 525);
FORCEPROP 1 LAST PART_NUMBER BAM138K0003
J 0
(-1149 431);
DISPLAY 0.723404 (-1149 431);
PAINT GREEN (-1149 431);
DISPLAY INVISIBLE (-1149 431);
FORCEPROP 2 LAST PART_TYPE SMLF
J 0
(-1125 600);
DISPLAY 1.021277 (-1125 600);
FORCEPROP 2 LAST VALUE PJT138K
J 0
(-1125 550);
DISPLAY 1.021277 (-1125 550);
FORCEPROP 1 LAST MATERIAL IC
J 0
(-1149 376);
DISPLAY 0.723404 (-1149 376);
PAINT GREEN (-1149 376);
FORCEPROP 1 LAST LOCATION Q50
J 0
(-1149 501);
DISPLAY 0.723404 (-1149 501);
PAINT GREEN (-1149 501);
FORCEPROP 0 LASTPIN (-1250 725) $PN 3
R 1
J 0
(-1260 735);
DISPLAY 0.680851 (-1260 735);
PAINT MONO (-1260 735);
FORCEPROP 0 LASTPIN (-1500 475) $PN 5
J 2
(-1510 485);
DISPLAY 0.680851 (-1510 485);
PAINT MONO (-1510 485);
FORCEPROP 0 LASTPIN (-1250 325) $PN 4
R 1
J 2
(-1260 315);
DISPLAY 0.680851 (-1260 315);
PAINT MONO (-1260 315);
FORCEPROP 2 LAST CDS_LIB pure_quanta
J 0
(-1300 525);
DISPLAY INVISIBLE (-1300 525);
FORCEPROP 1 LAST CDS_LMAN_SYM_OUTLINE -150,150,150,-150
J 0
(-1300 525);
DISPLAY 0.468085 (-1300 525);
PAINT GREEN (-1300 525);
DISPLAY INVISIBLE (-1300 525);
FORCEPROP 1 LAST NEEDS_NO_SIZE TRUE
J 0
(-1150 416);
DISPLAY 0.468085 (-1150 416);
PAINT GREEN (-1150 416);
DISPLAY INVISIBLE (-1150 416);
FORCEPROP 1 LAST PATH I49
J 0
(-1150 375);
DISPLAY 0.723404 (-1150 375);
PAINT GREEN (-1150 375);
DISPLAY INVISIBLE (-1150 375);
FORCEPROP 0 LAST $SEC 2
J 0
(-1125 650);
DISPLAY 0.680851 (-1125 650);
PAINT MONO (-1125 650);
DISPLAY INVISIBLE (-1125 650);
FORCEPROP 0 LAST CDS_SEC 2
J 0
(-1125 650);
DISPLAY 1.021277 (-1125 650);
DISPLAY INVISIBLE (-1125 650);
FORCEADD OFFPAGE..2
R 2
(-3425 -1250);
FORCEPROP 2 LAST $XR0 147 
J 0
(-3680 -1250);
DISPLAY 0.638298 (-3680 -1250);
PAINT MONO (-3680 -1250);
FORCEPROP 2 LAST PATH I5
J 0
(-3675 -1200);
DISPLAY 1.021277 (-3675 -1200);
DISPLAY INVISIBLE (-3675 -1200);
FORCEPROP 1 LAST COMMENT_BODY TRUE
J 2
(-3380 -1345);
DISPLAY 1.170213 (-3380 -1345);
PAINT GREEN (-3380 -1345);
DISPLAY INVISIBLE (-3380 -1345);
FORCEPROP 1 LAST OFFPAGE TRUE
J 2
(-3750 -1375);
DISPLAY 1.170213 (-3750 -1375);
PAINT GREEN (-3750 -1375);
DISPLAY INVISIBLE (-3750 -1375);
FORCEPROP 2 LAST CDS_LIB standard
J 0
(-3425 -1250);
DISPLAY INVISIBLE (-3425 -1250);
FORCEADD UNIVERSAL_GND..1
(-1250 225);
FORCEPROP 3 LASTPIN (-1250 275) SIG_NAME GND\g
J 0
(-1240 285);
DISPLAY 0.659574 (-1240 285);
PAINT MONO (-1240 285);
DISPLAY INVISIBLE (-1240 285);
FORCEPROP 2 LAST CDS_LIB logical_power
J 0
(-1250 225);
DISPLAY INVISIBLE (-1250 225);
FORCEPROP 1 LAST HDL_POWER GND
J 1
(-1225 150);
DISPLAY 0.872340 (-1225 150);
PAINT GREEN (-1225 150);
DISPLAY INVISIBLE (-1225 150);
FORCEPROP 1 LAST PATH I50
J 0
(-1175 225);
DISPLAY 0.872340 (-1175 225);
PAINT AQUA (-1175 225);
DISPLAY INVISIBLE (-1175 225);
FORCEADD Q_RES..2
(-1250 1050);
FORCEPROP 1 LAST PART_NUMBER CS24702JB10
J 0
(-1210 925);
DISPLAY 0.510638 (-1210 925);
DISPLAY INVISIBLE (-1210 925);
FORCEPROP 1 LAST PACK_TYPE 0402LF
J 0
(-1210 875);
DISPLAY 0.510638 (-1210 875);
FORCEPROP 1 LAST MATERIAL CHIP
J 0
(-1210 975);
DISPLAY 0.510638 (-1210 975);
FORCEPROP 1 LAST WATTAGE 1/16W
J 0
(-1210 1025);
DISPLAY 0.510638 (-1210 1025);
FORCEPROP 1 LAST TOLERANCE 5%
J 0
(-1205 1075);
DISPLAY 0.510638 (-1205 1075);
FORCEPROP 1 LAST VALUE 4.7K
J 0
(-1205 1125);
DISPLAY 0.510638 (-1205 1125);
FORCEPROP 1 LAST $LOCATION R2346
J 0
(-1205 1175);
DISPLAY 0.978723 (-1205 1175);
FORCEPROP 1 LASTPIN (-1250 1150) $PN 1
J 0
(-1245 1112);
DISPLAY 0.787234 (-1245 1112);
PAINT MONO (-1245 1112);
FORCEPROP 1 LASTPIN (-1250 950) $PN 2
J 0
(-1245 960);
DISPLAY 0.787234 (-1245 960);
PAINT MONO (-1245 960);
FORCEPROP 2 LAST CDS_LIB pure_quanta
J 0
(-1250 1050);
DISPLAY INVISIBLE (-1250 1050);
FORCEPROP 1 LAST PATH I51
J 0
(-1200 1225);
DISPLAY 0.978723 (-1200 1225);
PAINT WHITE (-1200 1225);
DISPLAY INVISIBLE (-1200 1225);
FORCEPROP 0 LAST CDS_LOCATION R2346
J 0
(-1200 1225);
DISPLAY 1.021277 (-1200 1225);
DISPLAY INVISIBLE (-1200 1225);
FORCEPROP 0 LAST $SEC 1
J 0
(-1200 1225);
DISPLAY 0.680851 (-1200 1225);
PAINT MONO (-1200 1225);
DISPLAY INVISIBLE (-1200 1225);
FORCEPROP 0 LAST CDS_SEC 1
J 0
(-1200 1225);
DISPLAY 1.021277 (-1200 1225);
DISPLAY INVISIBLE (-1200 1225);
FORCEADD UNIVERSAL_POWER..1
(-1250 1300);
FORCEPROP 3 LASTPIN (-1250 1250) SIG_NAME P3V3_AUX\g
J 0
(-1240 1260);
DISPLAY 0.659574 (-1240 1260);
PAINT MONO (-1240 1260);
DISPLAY INVISIBLE (-1240 1260);
FORCEPROP 1 LAST HDL_POWER P3V3_AUX
J 1
(-1250 1350);
DISPLAY 0.872340 (-1250 1350);
PAINT GREEN (-1250 1350);
FORCEPROP 2 LAST CDS_LIB logical_power
J 0
(-1250 1300);
DISPLAY INVISIBLE (-1250 1300);
FORCEPROP 1 LAST PATH I52
J 0
(-1200 1325);
DISPLAY 0.872340 (-1200 1325);
PAINT AQUA (-1200 1325);
DISPLAY INVISIBLE (-1200 1325);
FORCEADD OFFPAGE..5
(-1500 1625);
FORCEPROP 2 LAST $XR0 213 
J 0
(-1755 1625);
DISPLAY 0.638298 (-1755 1625);
PAINT MONO (-1755 1625);
FORCEPROP 2 LAST PATH I53
J 0
(-1750 1675);
DISPLAY 1.021277 (-1750 1675);
DISPLAY INVISIBLE (-1750 1675);
FORCEPROP 2 LAST CDS_LIB standard
J 0
(-1500 1625);
DISPLAY INVISIBLE (-1500 1625);
FORCEPROP 1 LAST OFFPAGE TRUE
J 0
(-1175 1500);
DISPLAY 0.872340 (-1175 1500);
DISPLAY INVISIBLE (-1175 1500);
FORCEPROP 1 LAST COMMENT_BODY TRUE
J 0
(-1400 1550);
DISPLAY 1.170213 (-1400 1550);
PAINT GREEN (-1400 1550);
DISPLAY INVISIBLE (-1400 1550);
FORCEADD OFFPAGE..1
(-1500 1575);
FORCEPROP 2 LAST $XR0 213 
J 0
(-1752 1575);
DISPLAY 0.638298 (-1752 1575);
PAINT MONO (-1752 1575);
FORCEPROP 2 LAST PATH I54
J 0
(-1750 1625);
DISPLAY 1.021277 (-1750 1625);
DISPLAY INVISIBLE (-1750 1625);
FORCEPROP 2 LAST CDS_LIB standard
J 0
(-1500 1575);
DISPLAY INVISIBLE (-1500 1575);
FORCEPROP 1 LAST COMMENT_BODY TRUE
J 0
(-1375 1475);
DISPLAY 1.170213 (-1375 1475);
PAINT GREEN (-1375 1475);
DISPLAY INVISIBLE (-1375 1475);
FORCEPROP 1 LAST OFFPAGE TRUE
J 0
(-1175 1450);
DISPLAY 1.170213 (-1175 1450);
PAINT GREEN (-1175 1450);
DISPLAY INVISIBLE (-1175 1450);
FORCEADD OFFPAGE..1
(-1500 1525);
FORCEPROP 2 LAST $XR0 213 
J 0
(-1752 1525);
DISPLAY 0.638298 (-1752 1525);
PAINT MONO (-1752 1525);
FORCEPROP 2 LAST PATH I55
J 0
(-1750 1575);
DISPLAY 1.021277 (-1750 1575);
DISPLAY INVISIBLE (-1750 1575);
FORCEPROP 1 LAST OFFPAGE TRUE
J 0
(-1175 1400);
DISPLAY 1.170213 (-1175 1400);
PAINT GREEN (-1175 1400);
DISPLAY INVISIBLE (-1175 1400);
FORCEPROP 1 LAST COMMENT_BODY TRUE
J 0
(-1375 1425);
DISPLAY 1.170213 (-1375 1425);
PAINT GREEN (-1375 1425);
DISPLAY INVISIBLE (-1375 1425);
FORCEPROP 2 LAST CDS_LIB standard
J 0
(-1500 1525);
DISPLAY INVISIBLE (-1500 1525);
FORCEADD OFFPAGE..1
(-1500 1675);
FORCEPROP 2 LAST $XR0 213 
J 0
(-1752 1675);
DISPLAY 0.638298 (-1752 1675);
PAINT MONO (-1752 1675);
FORCEPROP 2 LAST PATH I56
J 0
(-1750 1725);
DISPLAY 1.021277 (-1750 1725);
DISPLAY INVISIBLE (-1750 1725);
FORCEPROP 1 LAST OFFPAGE TRUE
J 0
(-1175 1550);
DISPLAY 1.170213 (-1175 1550);
PAINT GREEN (-1175 1550);
DISPLAY INVISIBLE (-1175 1550);
FORCEPROP 1 LAST COMMENT_BODY TRUE
J 0
(-1375 1575);
DISPLAY 1.170213 (-1375 1575);
PAINT GREEN (-1375 1575);
DISPLAY INVISIBLE (-1375 1575);
FORCEPROP 2 LAST CDS_LIB standard
J 0
(-1500 1675);
DISPLAY INVISIBLE (-1500 1675);
FORCEADD OFFPAGE..5
(-1500 1775);
FORCEPROP 2 LAST $XR0 213 
J 0
(-1755 1775);
DISPLAY 0.638298 (-1755 1775);
PAINT MONO (-1755 1775);
FORCEPROP 2 LAST PATH I57
J 0
(-1750 1825);
DISPLAY 1.021277 (-1750 1825);
DISPLAY INVISIBLE (-1750 1825);
FORCEPROP 1 LAST COMMENT_BODY TRUE
J 0
(-1400 1700);
DISPLAY 1.170213 (-1400 1700);
PAINT GREEN (-1400 1700);
DISPLAY INVISIBLE (-1400 1700);
FORCEPROP 1 LAST OFFPAGE TRUE
J 0
(-1175 1650);
DISPLAY 0.872340 (-1175 1650);
DISPLAY INVISIBLE (-1175 1650);
FORCEPROP 2 LAST CDS_LIB standard
J 0
(-1500 1775);
DISPLAY INVISIBLE (-1500 1775);
FORCEADD OFFPAGE..5
(-1500 1825);
FORCEPROP 2 LAST $XR0 213 
J 0
(-1755 1825);
DISPLAY 0.638298 (-1755 1825);
PAINT MONO (-1755 1825);
FORCEPROP 2 LAST PATH I58
J 0
(-1750 1875);
DISPLAY 1.021277 (-1750 1875);
DISPLAY INVISIBLE (-1750 1875);
FORCEPROP 1 LAST OFFPAGE TRUE
J 0
(-1175 1700);
DISPLAY 0.872340 (-1175 1700);
DISPLAY INVISIBLE (-1175 1700);
FORCEPROP 1 LAST COMMENT_BODY TRUE
J 0
(-1400 1750);
DISPLAY 1.170213 (-1400 1750);
PAINT GREEN (-1400 1750);
DISPLAY INVISIBLE (-1400 1750);
FORCEPROP 2 LAST CDS_LIB standard
J 0
(-1500 1825);
DISPLAY INVISIBLE (-1500 1825);
FORCEADD OFFPAGE..1
(-1500 1975);
FORCEPROP 2 LAST $XR0 213 
J 0
(-1752 1975);
DISPLAY 0.638298 (-1752 1975);
PAINT MONO (-1752 1975);
FORCEPROP 1 LAST COMMENT_BODY TRUE
J 0
(-1375 1875);
DISPLAY 1.170213 (-1375 1875);
PAINT GREEN (-1375 1875);
DISPLAY INVISIBLE (-1375 1875);
FORCEPROP 1 LAST OFFPAGE TRUE
J 0
(-1175 1850);
DISPLAY 1.170213 (-1175 1850);
PAINT GREEN (-1175 1850);
DISPLAY INVISIBLE (-1175 1850);
FORCEPROP 2 LAST PATH I59
J 0
(-1750 2025);
DISPLAY 1.021277 (-1750 2025);
DISPLAY INVISIBLE (-1750 2025);
FORCEPROP 2 LAST CDS_LIB standard
J 0
(-1500 1975);
DISPLAY INVISIBLE (-1500 1975);
FORCEADD OFFPAGE..1
(-3425 -750);
FORCEPROP 2 LAST $XR0 147 
J 0
(-3677 -750);
DISPLAY 0.638298 (-3677 -750);
PAINT MONO (-3677 -750);
FORCEPROP 2 LAST PATH I6
J 0
(-3675 -700);
DISPLAY 1.021277 (-3675 -700);
DISPLAY INVISIBLE (-3675 -700);
FORCEPROP 1 LAST OFFPAGE TRUE
J 0
(-3100 -875);
DISPLAY 0.872340 (-3100 -875);
DISPLAY INVISIBLE (-3100 -875);
FORCEPROP 1 LAST COMMENT_BODY TRUE
J 0
(-3300 -850);
DISPLAY 1.170213 (-3300 -850);
PAINT GREEN (-3300 -850);
DISPLAY INVISIBLE (-3300 -850);
FORCEPROP 2 LAST CDS_LIB standard
J 0
(-3425 -750);
DISPLAY INVISIBLE (-3425 -750);
FORCEADD OFFPAGE..1
(-1500 2025);
FORCEPROP 2 LAST $XR0 213 
J 0
(-1752 2025);
DISPLAY 0.638298 (-1752 2025);
PAINT MONO (-1752 2025);
FORCEPROP 2 LAST PATH I60
J 0
(-1750 2075);
DISPLAY 1.021277 (-1750 2075);
DISPLAY INVISIBLE (-1750 2075);
FORCEPROP 1 LAST COMMENT_BODY TRUE
J 0
(-1375 1925);
DISPLAY 1.170213 (-1375 1925);
PAINT GREEN (-1375 1925);
DISPLAY INVISIBLE (-1375 1925);
FORCEPROP 1 LAST OFFPAGE TRUE
J 0
(-1175 1900);
DISPLAY 1.170213 (-1175 1900);
PAINT GREEN (-1175 1900);
DISPLAY INVISIBLE (-1175 1900);
FORCEPROP 2 LAST CDS_LIB standard
J 0
(-1500 2025);
DISPLAY INVISIBLE (-1500 2025);
FORCEADD OFFPAGE..2
(-500 800);
FORCEPROP 2 LAST $XR0 213 
J 0
(-311 800);
DISPLAY 0.638298 (-311 800);
PAINT MONO (-311 800);
FORCEPROP 1 LAST COMMENT_BODY TRUE
J 0
(-545 705);
DISPLAY 0.872340 (-545 705);
PAINT GREEN (-545 705);
DISPLAY INVISIBLE (-545 705);
FORCEPROP 1 LAST OFFPAGE TRUE
J 0
(-175 675);
DISPLAY 0.872340 (-175 675);
PAINT GREEN (-175 675);
DISPLAY INVISIBLE (-175 675);
FORCEPROP 2 LAST CDS_LIB standard
J 0
(-500 800);
DISPLAY INVISIBLE (-500 800);
FORCEPROP 2 LAST PATH I61
J 0
(-300 850);
DISPLAY 1.021277 (-300 850);
DISPLAY INVISIBLE (-300 850);
FORCEADD OFFPAGE..5
(-1500 2175);
FORCEPROP 2 LAST $XR0 213 
J 0
(-1755 2175);
DISPLAY 0.638298 (-1755 2175);
PAINT MONO (-1755 2175);
FORCEPROP 2 LAST PATH I62
J 0
(-1750 2225);
DISPLAY 1.021277 (-1750 2225);
DISPLAY INVISIBLE (-1750 2225);
FORCEPROP 1 LAST OFFPAGE TRUE
J 0
(-1175 2050);
DISPLAY 0.872340 (-1175 2050);
DISPLAY INVISIBLE (-1175 2050);
FORCEPROP 1 LAST COMMENT_BODY TRUE
J 0
(-1400 2100);
DISPLAY 1.170213 (-1400 2100);
PAINT GREEN (-1400 2100);
DISPLAY INVISIBLE (-1400 2100);
FORCEPROP 2 LAST CDS_LIB standard
J 0
(-1500 2175);
DISPLAY INVISIBLE (-1500 2175);
FORCEADD OFFPAGE..5
(-1500 2125);
FORCEPROP 2 LAST $XR0 213 
J 0
(-1755 2125);
DISPLAY 0.638298 (-1755 2125);
PAINT MONO (-1755 2125);
FORCEPROP 2 LAST PATH I63
J 0
(-1750 2175);
DISPLAY 1.021277 (-1750 2175);
DISPLAY INVISIBLE (-1750 2175);
FORCEPROP 1 LAST OFFPAGE TRUE
J 0
(-1175 2000);
DISPLAY 0.872340 (-1175 2000);
DISPLAY INVISIBLE (-1175 2000);
FORCEPROP 1 LAST COMMENT_BODY TRUE
J 0
(-1400 2050);
DISPLAY 1.170213 (-1400 2050);
PAINT GREEN (-1400 2050);
DISPLAY INVISIBLE (-1400 2050);
FORCEPROP 2 LAST CDS_LIB standard
J 0
(-1500 2125);
DISPLAY INVISIBLE (-1500 2125);
FORCEADD OFFPAGE..5
(-1500 2075);
FORCEPROP 2 LAST $XR0 213 
J 0
(-1755 2075);
DISPLAY 0.638298 (-1755 2075);
PAINT MONO (-1755 2075);
FORCEPROP 2 LAST PATH I64
J 0
(-1750 2125);
DISPLAY 1.021277 (-1750 2125);
DISPLAY INVISIBLE (-1750 2125);
FORCEPROP 1 LAST OFFPAGE TRUE
J 0
(-1175 1950);
DISPLAY 0.872340 (-1175 1950);
DISPLAY INVISIBLE (-1175 1950);
FORCEPROP 1 LAST COMMENT_BODY TRUE
J 0
(-1400 2000);
DISPLAY 1.170213 (-1400 2000);
PAINT GREEN (-1400 2000);
DISPLAY INVISIBLE (-1400 2000);
FORCEPROP 2 LAST CDS_LIB standard
J 0
(-1500 2075);
DISPLAY INVISIBLE (-1500 2075);
FORCEADD OFFPAGE..1
(-1500 2225);
FORCEPROP 2 LAST $XR0 213 
J 0
(-1752 2225);
DISPLAY 0.638298 (-1752 2225);
PAINT MONO (-1752 2225);
FORCEPROP 2 LAST PATH I65
J 0
(-1750 2275);
DISPLAY 1.021277 (-1750 2275);
DISPLAY INVISIBLE (-1750 2275);
FORCEPROP 2 LAST CDS_LIB standard
J 0
(-1500 2225);
DISPLAY INVISIBLE (-1500 2225);
FORCEPROP 1 LAST OFFPAGE TRUE
J 0
(-1175 2100);
DISPLAY 1.170213 (-1175 2100);
PAINT GREEN (-1175 2100);
DISPLAY INVISIBLE (-1175 2100);
FORCEPROP 1 LAST COMMENT_BODY TRUE
J 0
(-1375 2125);
DISPLAY 1.170213 (-1375 2125);
PAINT GREEN (-1375 2125);
DISPLAY INVISIBLE (-1375 2125);
FORCEADD OFFPAGE..1
(-1500 2475);
FORCEPROP 2 LAST $XR0 183 
J 0
(-1752 2475);
DISPLAY 0.638298 (-1752 2475);
PAINT MONO (-1752 2475);
FORCEPROP 2 LAST PATH I66
J 0
(-1750 2525);
DISPLAY 1.021277 (-1750 2525);
DISPLAY INVISIBLE (-1750 2525);
FORCEPROP 2 LAST CDS_LIB standard
J 0
(-1500 2475);
DISPLAY INVISIBLE (-1500 2475);
FORCEPROP 1 LAST COMMENT_BODY TRUE
J 0
(-1375 2375);
DISPLAY 1.170213 (-1375 2375);
PAINT GREEN (-1375 2375);
DISPLAY INVISIBLE (-1375 2375);
FORCEPROP 1 LAST OFFPAGE TRUE
J 0
(-1175 2350);
DISPLAY 0.872340 (-1175 2350);
DISPLAY INVISIBLE (-1175 2350);
FORCEADD OFFPAGE..1
(-1500 2425);
FORCEPROP 2 LAST $XR1 220 
J 0
(-1872 2425);
DISPLAY 0.638298 (-1872 2425);
PAINT MONO (-1872 2425);
FORCEPROP 2 LAST $XR0 182 
J 0
(-1752 2425);
DISPLAY 0.638298 (-1752 2425);
PAINT MONO (-1752 2425);
FORCEPROP 2 LAST PATH I67
J 0
(-1750 2475);
DISPLAY 1.021277 (-1750 2475);
DISPLAY INVISIBLE (-1750 2475);
FORCEPROP 1 LAST OFFPAGE TRUE
J 0
(-1175 2300);
DISPLAY 0.872340 (-1175 2300);
DISPLAY INVISIBLE (-1175 2300);
FORCEPROP 1 LAST COMMENT_BODY TRUE
J 0
(-1375 2325);
DISPLAY 1.170213 (-1375 2325);
PAINT GREEN (-1375 2325);
DISPLAY INVISIBLE (-1375 2325);
FORCEPROP 2 LAST CDS_LIB standard
J 0
(-1500 2425);
DISPLAY INVISIBLE (-1500 2425);
FORCEADD OFFPAGE..5
(-1500 2525);
FORCEPROP 2 LAST $XR1 228 
J 0
(-1875 2525);
DISPLAY 0.638298 (-1875 2525);
PAINT MONO (-1875 2525);
FORCEPROP 2 LAST $XR0 183 
J 0
(-1755 2525);
DISPLAY 0.638298 (-1755 2525);
PAINT MONO (-1755 2525);
FORCEPROP 2 LAST PATH I68
J 0
(-1750 2575);
DISPLAY 1.021277 (-1750 2575);
DISPLAY INVISIBLE (-1750 2575);
FORCEPROP 2 LAST CDS_LIB standard
J 0
(-1500 2525);
DISPLAY INVISIBLE (-1500 2525);
FORCEPROP 1 LAST OFFPAGE TRUE
J 0
(-1175 2400);
DISPLAY 0.872340 (-1175 2400);
DISPLAY INVISIBLE (-1175 2400);
FORCEPROP 1 LAST COMMENT_BODY TRUE
J 0
(-1400 2450);
DISPLAY 1.170213 (-1400 2450);
PAINT GREEN (-1400 2450);
DISPLAY INVISIBLE (-1400 2450);
FORCEADD OFFPAGE..5
(-1500 2625);
FORCEPROP 2 LAST $XR0 213 
J 0
(-1755 2625);
DISPLAY 0.638298 (-1755 2625);
PAINT MONO (-1755 2625);
FORCEPROP 2 LAST PATH I69
J 0
(-1750 2675);
DISPLAY 1.021277 (-1750 2675);
DISPLAY INVISIBLE (-1750 2675);
FORCEPROP 2 LAST CDS_LIB standard
J 0
(-1500 2625);
DISPLAY INVISIBLE (-1500 2625);
FORCEPROP 1 LAST COMMENT_BODY TRUE
J 0
(-1400 2550);
DISPLAY 1.170213 (-1400 2550);
PAINT GREEN (-1400 2550);
DISPLAY INVISIBLE (-1400 2550);
FORCEPROP 1 LAST OFFPAGE TRUE
J 0
(-1175 2500);
DISPLAY 0.872340 (-1175 2500);
DISPLAY INVISIBLE (-1175 2500);
FORCEADD OFFPAGE..1
(-3425 -625);
FORCEPROP 2 LAST $XR0 147 
J 0
(-3677 -625);
DISPLAY 0.638298 (-3677 -625);
PAINT MONO (-3677 -625);
FORCEPROP 2 LAST PATH I7
J 0
(-3675 -575);
DISPLAY 1.021277 (-3675 -575);
DISPLAY INVISIBLE (-3675 -575);
FORCEPROP 2 LAST CDS_LIB standard
J 0
(-3425 -625);
DISPLAY INVISIBLE (-3425 -625);
FORCEPROP 1 LAST COMMENT_BODY TRUE
J 0
(-3300 -725);
DISPLAY 1.170213 (-3300 -725);
PAINT GREEN (-3300 -725);
DISPLAY INVISIBLE (-3300 -725);
FORCEPROP 1 LAST OFFPAGE TRUE
J 0
(-3100 -750);
DISPLAY 0.872340 (-3100 -750);
DISPLAY INVISIBLE (-3100 -750);
FORCEADD OFFPAGE..5
(-1500 2575);
FORCEPROP 2 LAST $XR0 183 
J 0
(-1755 2575);
DISPLAY 0.638298 (-1755 2575);
PAINT MONO (-1755 2575);
FORCEPROP 2 LAST PATH I70
J 0
(-1750 2625);
DISPLAY 1.021277 (-1750 2625);
DISPLAY INVISIBLE (-1750 2625);
FORCEPROP 1 LAST OFFPAGE TRUE
J 0
(-1175 2450);
DISPLAY 0.872340 (-1175 2450);
DISPLAY INVISIBLE (-1175 2450);
FORCEPROP 1 LAST COMMENT_BODY TRUE
J 0
(-1400 2500);
DISPLAY 1.170213 (-1400 2500);
PAINT GREEN (-1400 2500);
DISPLAY INVISIBLE (-1400 2500);
FORCEPROP 2 LAST CDS_LIB standard
J 0
(-1500 2575);
DISPLAY INVISIBLE (-1500 2575);
FORCEADD OFFPAGE..1
(-1500 2675);
FORCEPROP 2 LAST $XR1 80 
J 0
(-1811 2675);
DISPLAY 0.638298 (-1811 2675);
PAINT MONO (-1811 2675);
FORCEPROP 2 LAST $XR0 46 
J 0
(-1721 2675);
DISPLAY 0.638298 (-1721 2675);
PAINT MONO (-1721 2675);
FORCEPROP 2 LAST PATH I71
J 0
(-1700 2725);
DISPLAY 1.021277 (-1700 2725);
DISPLAY INVISIBLE (-1700 2725);
FORCEPROP 1 LAST OFFPAGE TRUE
J 0
(-1175 2550);
DISPLAY 0.872340 (-1175 2550);
DISPLAY INVISIBLE (-1175 2550);
FORCEPROP 1 LAST COMMENT_BODY TRUE
J 0
(-1375 2575);
DISPLAY 1.170213 (-1375 2575);
PAINT GREEN (-1375 2575);
DISPLAY INVISIBLE (-1375 2575);
FORCEPROP 2 LAST CDS_LIB standard
J 0
(-1500 2675);
DISPLAY INVISIBLE (-1500 2675);
FORCEADD OFFPAGE..1
(-1500 2725);
FORCEPROP 2 LAST $XR1 80 
J 0
(-1811 2725);
DISPLAY 0.638298 (-1811 2725);
PAINT MONO (-1811 2725);
FORCEPROP 2 LAST $XR0 15 
J 0
(-1721 2725);
DISPLAY 0.638298 (-1721 2725);
PAINT MONO (-1721 2725);
FORCEPROP 2 LAST PATH I72
J 0
(-1700 2775);
DISPLAY 1.021277 (-1700 2775);
DISPLAY INVISIBLE (-1700 2775);
FORCEPROP 1 LAST OFFPAGE TRUE
J 0
(-1175 2600);
DISPLAY 0.872340 (-1175 2600);
DISPLAY INVISIBLE (-1175 2600);
FORCEPROP 1 LAST COMMENT_BODY TRUE
J 0
(-1375 2625);
DISPLAY 1.170213 (-1375 2625);
PAINT GREEN (-1375 2625);
DISPLAY INVISIBLE (-1375 2625);
FORCEPROP 2 LAST CDS_LIB standard
J 0
(-1500 2725);
DISPLAY INVISIBLE (-1500 2725);
FORCEADD OFFPAGE..1
(-1500 2775);
FORCEPROP 2 LAST $XR0 213 
J 0
(-1752 2775);
DISPLAY 0.638298 (-1752 2775);
PAINT MONO (-1752 2775);
FORCEPROP 2 LAST PATH I73
J 0
(-1750 2825);
DISPLAY 1.021277 (-1750 2825);
DISPLAY INVISIBLE (-1750 2825);
FORCEPROP 1 LAST COMMENT_BODY TRUE
J 0
(-1375 2675);
DISPLAY 1.170213 (-1375 2675);
PAINT GREEN (-1375 2675);
DISPLAY INVISIBLE (-1375 2675);
FORCEPROP 1 LAST OFFPAGE TRUE
J 0
(-1175 2650);
DISPLAY 1.170213 (-1175 2650);
PAINT GREEN (-1175 2650);
DISPLAY INVISIBLE (-1175 2650);
FORCEPROP 2 LAST CDS_LIB standard
J 2
(-1500 2775);
PAINT MONO (-1500 2775);
DISPLAY INVISIBLE (-1500 2775);
FORCEADD OFFPAGE..5
(-1500 2975);
FORCEPROP 2 LAST $XR0 197 
J 0
(-1755 2975);
DISPLAY 0.638298 (-1755 2975);
PAINT MONO (-1755 2975);
FORCEPROP 2 LAST PATH I74
J 0
(-1750 3025);
DISPLAY 1.021277 (-1750 3025);
DISPLAY INVISIBLE (-1750 3025);
FORCEPROP 2 LAST CDS_LIB standard
J 0
(-1500 2975);
DISPLAY INVISIBLE (-1500 2975);
FORCEPROP 1 LAST OFFPAGE TRUE
J 0
(-1175 2850);
DISPLAY 0.872340 (-1175 2850);
DISPLAY INVISIBLE (-1175 2850);
FORCEPROP 1 LAST COMMENT_BODY TRUE
J 0
(-1400 2900);
DISPLAY 1.170213 (-1400 2900);
PAINT GREEN (-1400 2900);
DISPLAY INVISIBLE (-1400 2900);
FORCEADD OFFPAGE..5
(-1500 2875);
FORCEPROP 2 LAST $XR0 158 
J 0
(-1755 2875);
DISPLAY 0.638298 (-1755 2875);
PAINT MONO (-1755 2875);
FORCEPROP 2 LAST PATH I75
J 0
(-1750 2925);
DISPLAY 1.021277 (-1750 2925);
DISPLAY INVISIBLE (-1750 2925);
FORCEPROP 2 LAST CDS_LIB standard
J 0
(-1500 2875);
DISPLAY INVISIBLE (-1500 2875);
FORCEPROP 1 LAST COMMENT_BODY TRUE
J 0
(-1400 2800);
DISPLAY 1.170213 (-1400 2800);
PAINT GREEN (-1400 2800);
DISPLAY INVISIBLE (-1400 2800);
FORCEPROP 1 LAST OFFPAGE TRUE
J 0
(-1175 2750);
DISPLAY 0.872340 (-1175 2750);
DISPLAY INVISIBLE (-1175 2750);
FORCEADD OFFPAGE..2
R 2
(-1500 2925);
FORCEPROP 2 LAST $XR0 164 
J 0
(-1755 2925);
DISPLAY 0.638298 (-1755 2925);
PAINT MONO (-1755 2925);
FORCEPROP 2 LAST PATH I76
J 0
(-1750 2975);
DISPLAY 1.021277 (-1750 2975);
DISPLAY INVISIBLE (-1750 2975);
FORCEPROP 1 LAST OFFPAGE TRUE
J 2
(-1825 2800);
DISPLAY 1.170213 (-1825 2800);
PAINT GREEN (-1825 2800);
DISPLAY INVISIBLE (-1825 2800);
FORCEPROP 1 LAST COMMENT_BODY TRUE
J 2
(-1455 2830);
DISPLAY 1.170213 (-1455 2830);
PAINT GREEN (-1455 2830);
DISPLAY INVISIBLE (-1455 2830);
FORCEPROP 2 LAST CDS_LIB standard
J 2
(-1500 2925);
DISPLAY INVISIBLE (-1500 2925);
FORCEADD OFFPAGE..1
(-1500 2825);
FORCEPROP 2 LAST $XR0 213 
J 0
(-1752 2825);
DISPLAY 0.638298 (-1752 2825);
PAINT MONO (-1752 2825);
FORCEPROP 2 LAST PATH I77
J 0
(-1750 2875);
DISPLAY 1.021277 (-1750 2875);
DISPLAY INVISIBLE (-1750 2875);
FORCEPROP 1 LAST COMMENT_BODY TRUE
J 0
(-1375 2725);
DISPLAY 1.170213 (-1375 2725);
PAINT GREEN (-1375 2725);
DISPLAY INVISIBLE (-1375 2725);
FORCEPROP 1 LAST OFFPAGE TRUE
J 0
(-1175 2700);
DISPLAY 1.170213 (-1175 2700);
PAINT GREEN (-1175 2700);
DISPLAY INVISIBLE (-1175 2700);
FORCEPROP 2 LAST CDS_LIB standard
J 2
(-1500 2825);
DISPLAY INVISIBLE (-1500 2825);
FORCEADD OFFPAGE..1
(-1500 3025);
FORCEPROP 2 LAST $XR0 213 
J 0
(-1752 3025);
DISPLAY 0.638298 (-1752 3025);
PAINT MONO (-1752 3025);
FORCEPROP 2 LAST PATH I78
J 0
(-1750 3075);
DISPLAY 1.021277 (-1750 3075);
DISPLAY INVISIBLE (-1750 3075);
FORCEPROP 1 LAST OFFPAGE TRUE
J 0
(-1175 2900);
DISPLAY 0.872340 (-1175 2900);
DISPLAY INVISIBLE (-1175 2900);
FORCEPROP 1 LAST COMMENT_BODY TRUE
J 0
(-1375 2925);
DISPLAY 1.170213 (-1375 2925);
PAINT GREEN (-1375 2925);
DISPLAY INVISIBLE (-1375 2925);
FORCEPROP 2 LAST CDS_LIB standard
J 0
(-1500 3025);
DISPLAY INVISIBLE (-1500 3025);
FORCEADD OFFPAGE..5
(-1500 3075);
FORCEPROP 2 LAST $XR0 213 
J 0
(-1755 3075);
DISPLAY 0.638298 (-1755 3075);
PAINT MONO (-1755 3075);
FORCEPROP 2 LAST PATH I79
J 0
(-1750 3125);
DISPLAY 1.021277 (-1750 3125);
DISPLAY INVISIBLE (-1750 3125);
FORCEPROP 1 LAST COMMENT_BODY TRUE
J 0
(-1400 3000);
DISPLAY 1.170213 (-1400 3000);
PAINT GREEN (-1400 3000);
DISPLAY INVISIBLE (-1400 3000);
FORCEPROP 1 LAST OFFPAGE TRUE
J 0
(-1175 2950);
DISPLAY 0.872340 (-1175 2950);
DISPLAY INVISIBLE (-1175 2950);
FORCEPROP 2 LAST CDS_LIB standard
J 0
(-1500 3075);
DISPLAY INVISIBLE (-1500 3075);
FORCEADD OFFPAGE..2
R 2
(-3425 -1000);
FORCEPROP 2 LAST $XR0 150 
J 0
(-3680 -1000);
DISPLAY 0.638298 (-3680 -1000);
PAINT MONO (-3680 -1000);
FORCEPROP 2 LAST PATH I8
J 0
(-3675 -950);
DISPLAY 1.021277 (-3675 -950);
DISPLAY INVISIBLE (-3675 -950);
FORCEPROP 2 LAST CDS_LIB standard
J 0
(-3425 -1000);
DISPLAY INVISIBLE (-3425 -1000);
FORCEPROP 1 LAST OFFPAGE TRUE
J 2
(-3750 -1125);
DISPLAY 1.170213 (-3750 -1125);
PAINT GREEN (-3750 -1125);
DISPLAY INVISIBLE (-3750 -1125);
FORCEPROP 1 LAST COMMENT_BODY TRUE
J 2
(-3380 -1095);
DISPLAY 1.170213 (-3380 -1095);
PAINT GREEN (-3380 -1095);
DISPLAY INVISIBLE (-3380 -1095);
FORCEADD OFFPAGE..5
(-1500 3125);
FORCEPROP 2 LAST $XR0 213 
J 0
(-1755 3125);
DISPLAY 0.638298 (-1755 3125);
PAINT MONO (-1755 3125);
FORCEPROP 2 LAST PATH I80
J 0
(-1750 3175);
DISPLAY 1.021277 (-1750 3175);
DISPLAY INVISIBLE (-1750 3175);
FORCEPROP 2 LAST CDS_LIB standard
J 0
(-1500 3125);
DISPLAY INVISIBLE (-1500 3125);
FORCEPROP 1 LAST COMMENT_BODY TRUE
J 0
(-1400 3050);
DISPLAY 1.170213 (-1400 3050);
PAINT GREEN (-1400 3050);
DISPLAY INVISIBLE (-1400 3050);
FORCEPROP 1 LAST OFFPAGE TRUE
J 0
(-1175 3000);
DISPLAY 0.872340 (-1175 3000);
DISPLAY INVISIBLE (-1175 3000);
FORCEADD OFFPAGE..5
(-1500 3175);
FORCEPROP 2 LAST $XR0 213 
J 0
(-1755 3175);
DISPLAY 0.638298 (-1755 3175);
PAINT MONO (-1755 3175);
FORCEPROP 2 LAST PATH I81
J 0
(-1750 3225);
DISPLAY 1.021277 (-1750 3225);
DISPLAY INVISIBLE (-1750 3225);
FORCEPROP 2 LAST CDS_LIB standard
J 0
(-1500 3175);
DISPLAY INVISIBLE (-1500 3175);
FORCEPROP 1 LAST COMMENT_BODY TRUE
J 0
(-1400 3100);
DISPLAY 1.170213 (-1400 3100);
PAINT GREEN (-1400 3100);
DISPLAY INVISIBLE (-1400 3100);
FORCEPROP 1 LAST OFFPAGE TRUE
J 0
(-1175 3050);
DISPLAY 0.872340 (-1175 3050);
DISPLAY INVISIBLE (-1175 3050);
FORCEADD OFFPAGE..1
(-1500 3225);
FORCEPROP 2 LAST $XR0 185 
J 0
(-1752 3225);
DISPLAY 0.638298 (-1752 3225);
PAINT MONO (-1752 3225);
FORCEPROP 2 LAST PATH I82
J 0
(-1750 3275);
DISPLAY 1.021277 (-1750 3275);
DISPLAY INVISIBLE (-1750 3275);
FORCEPROP 2 LAST CDS_LIB standard
J 0
(-1500 3225);
DISPLAY INVISIBLE (-1500 3225);
FORCEPROP 1 LAST COMMENT_BODY TRUE
J 0
(-1375 3125);
DISPLAY 1.170213 (-1375 3125);
PAINT GREEN (-1375 3125);
DISPLAY INVISIBLE (-1375 3125);
FORCEPROP 1 LAST OFFPAGE TRUE
J 0
(-1175 3100);
DISPLAY 1.170213 (-1175 3100);
PAINT GREEN (-1175 3100);
DISPLAY INVISIBLE (-1175 3100);
FORCEADD OFFPAGE..4
R 2
(-1500 3275);
FORCEPROP 2 LAST $XR0 234 
J 0
(-1752 3275);
DISPLAY 0.638298 (-1752 3275);
PAINT MONO (-1752 3275);
FORCEPROP 2 LAST PATH I83
J 0
(-1750 3325);
DISPLAY 1.021277 (-1750 3325);
DISPLAY INVISIBLE (-1750 3325);
FORCEPROP 2 LAST CDS_LIB standard
J 0
(-1500 3275);
DISPLAY INVISIBLE (-1500 3275);
FORCEPROP 1 LAST OFFPAGE TRUE
J 2
(-1825 3150);
DISPLAY 0.872340 (-1825 3150);
DISPLAY INVISIBLE (-1825 3150);
FORCEPROP 1 LAST COMMENT_BODY TRUE
J 2
(-1475 3175);
DISPLAY 0.872340 (-1475 3175);
PAINT GREEN (-1475 3175);
DISPLAY INVISIBLE (-1475 3175);
FORCEADD OFFPAGE..2
R 2
(-1500 3375);
FORCEPROP 2 LAST $XR0 234 
J 0
(-1755 3375);
DISPLAY 0.638298 (-1755 3375);
PAINT MONO (-1755 3375);
FORCEPROP 2 LAST PATH I84
J 0
(-1750 3425);
DISPLAY 1.021277 (-1750 3425);
DISPLAY INVISIBLE (-1750 3425);
FORCEPROP 1 LAST COMMENT_BODY TRUE
J 2
(-1455 3280);
DISPLAY 1.170213 (-1455 3280);
PAINT GREEN (-1455 3280);
DISPLAY INVISIBLE (-1455 3280);
FORCEPROP 1 LAST OFFPAGE TRUE
J 2
(-1825 3250);
DISPLAY 1.170213 (-1825 3250);
PAINT GREEN (-1825 3250);
DISPLAY INVISIBLE (-1825 3250);
FORCEPROP 2 LAST CDS_LIB standard
J 2
(-1500 3375);
DISPLAY INVISIBLE (-1500 3375);
FORCEADD OFFPAGE..2
R 2
(-1500 3475);
FORCEPROP 2 LAST $XR0 213 
J 0
(-1755 3475);
DISPLAY 0.638298 (-1755 3475);
PAINT MONO (-1755 3475);
FORCEPROP 2 LAST PATH I85
J 0
(-1750 3525);
DISPLAY 1.021277 (-1750 3525);
DISPLAY INVISIBLE (-1750 3525);
FORCEPROP 2 LAST CDS_LIB standard
J 2
(-1500 3475);
DISPLAY INVISIBLE (-1500 3475);
FORCEPROP 1 LAST COMMENT_BODY TRUE
J 2
(-1455 3380);
DISPLAY 1.170213 (-1455 3380);
PAINT GREEN (-1455 3380);
DISPLAY INVISIBLE (-1455 3380);
FORCEPROP 1 LAST OFFPAGE TRUE
J 2
(-1825 3350);
DISPLAY 1.170213 (-1825 3350);
PAINT GREEN (-1825 3350);
DISPLAY INVISIBLE (-1825 3350);
FORCEADD OFFPAGE..1
(-1500 3325);
FORCEPROP 2 LAST $XR0 213 
J 0
(-1752 3325);
DISPLAY 0.638298 (-1752 3325);
PAINT MONO (-1752 3325);
FORCEPROP 2 LAST PATH I86
J 0
(-1750 3375);
DISPLAY 1.021277 (-1750 3375);
DISPLAY INVISIBLE (-1750 3375);
FORCEPROP 1 LAST COMMENT_BODY TRUE
J 0
(-1375 3225);
DISPLAY 1.170213 (-1375 3225);
PAINT GREEN (-1375 3225);
DISPLAY INVISIBLE (-1375 3225);
FORCEPROP 1 LAST OFFPAGE TRUE
J 0
(-1175 3200);
DISPLAY 1.170213 (-1175 3200);
PAINT GREEN (-1175 3200);
DISPLAY INVISIBLE (-1175 3200);
FORCEPROP 2 LAST CDS_LIB standard
J 2
(-1500 3325);
DISPLAY INVISIBLE (-1500 3325);
FORCEADD OFFPAGE..1
(-1500 3425);
FORCEPROP 2 LAST $XR0 213 
J 0
(-1752 3425);
DISPLAY 0.638298 (-1752 3425);
PAINT MONO (-1752 3425);
FORCEPROP 2 LAST PATH I87
J 0
(-1750 3475);
DISPLAY 1.021277 (-1750 3475);
DISPLAY INVISIBLE (-1750 3475);
FORCEPROP 1 LAST COMMENT_BODY TRUE
J 0
(-1375 3325);
DISPLAY 1.170213 (-1375 3325);
PAINT GREEN (-1375 3325);
DISPLAY INVISIBLE (-1375 3325);
FORCEPROP 1 LAST OFFPAGE TRUE
J 0
(-1175 3300);
DISPLAY 1.170213 (-1175 3300);
PAINT GREEN (-1175 3300);
DISPLAY INVISIBLE (-1175 3300);
FORCEPROP 2 LAST CDS_LIB standard
J 2
(-1500 3425);
DISPLAY INVISIBLE (-1500 3425);
FORCEADD OFFPAGE..1
(-1500 3525);
FORCEPROP 2 LAST $XR0 213 
J 0
(-1752 3525);
DISPLAY 0.638298 (-1752 3525);
PAINT MONO (-1752 3525);
FORCEPROP 2 LAST PATH I88
J 0
(-1750 3575);
DISPLAY 1.021277 (-1750 3575);
DISPLAY INVISIBLE (-1750 3575);
FORCEPROP 1 LAST OFFPAGE TRUE
J 0
(-1175 3400);
DISPLAY 1.170213 (-1175 3400);
PAINT GREEN (-1175 3400);
DISPLAY INVISIBLE (-1175 3400);
FORCEPROP 1 LAST COMMENT_BODY TRUE
J 0
(-1375 3425);
DISPLAY 1.170213 (-1375 3425);
PAINT GREEN (-1375 3425);
DISPLAY INVISIBLE (-1375 3425);
FORCEPROP 2 LAST CDS_LIB standard
J 2
(-1500 3525);
DISPLAY INVISIBLE (-1500 3525);
FORCEADD OFFPAGE..5
(-1500 3625);
FORCEPROP 2 LAST $XR0 245 
J 0
(-1755 3625);
DISPLAY 0.638298 (-1755 3625);
PAINT MONO (-1755 3625);
FORCEPROP 2 LAST PATH I89
J 0
(-1750 3675);
DISPLAY 1.021277 (-1750 3675);
DISPLAY INVISIBLE (-1750 3675);
FORCEPROP 2 LAST CDS_LIB standard
J 0
(-1500 3625);
DISPLAY INVISIBLE (-1500 3625);
FORCEPROP 1 LAST COMMENT_BODY TRUE
J 0
(-1400 3550);
DISPLAY 1.170213 (-1400 3550);
PAINT GREEN (-1400 3550);
DISPLAY INVISIBLE (-1400 3550);
FORCEPROP 1 LAST OFFPAGE TRUE
J 0
(-1175 3500);
DISPLAY 0.872340 (-1175 3500);
DISPLAY INVISIBLE (-1175 3500);
FORCEADD OFFPAGE..2
R 2
(-3425 -875);
FORCEPROP 2 LAST $XR0 149 
J 0
(-3680 -875);
DISPLAY 0.638298 (-3680 -875);
PAINT MONO (-3680 -875);
FORCEPROP 2 LAST PATH I9
J 0
(-3675 -825);
DISPLAY 1.021277 (-3675 -825);
DISPLAY INVISIBLE (-3675 -825);
FORCEPROP 1 LAST COMMENT_BODY TRUE
J 2
(-3380 -970);
DISPLAY 1.170213 (-3380 -970);
PAINT GREEN (-3380 -970);
DISPLAY INVISIBLE (-3380 -970);
FORCEPROP 1 LAST OFFPAGE TRUE
J 2
(-3750 -1000);
DISPLAY 1.170213 (-3750 -1000);
PAINT GREEN (-3750 -1000);
DISPLAY INVISIBLE (-3750 -1000);
FORCEPROP 2 LAST CDS_LIB standard
J 0
(-3425 -875);
DISPLAY INVISIBLE (-3425 -875);
FORCEADD OFFPAGE..5
(-1500 3575);
FORCEPROP 2 LAST $XR0 213 
J 0
(-1755 3575);
DISPLAY 0.638298 (-1755 3575);
PAINT MONO (-1755 3575);
FORCEPROP 2 LAST PATH I90
J 0
(-1750 3625);
DISPLAY 1.021277 (-1750 3625);
DISPLAY INVISIBLE (-1750 3625);
FORCEPROP 2 LAST CDS_LIB standard
J 0
(-1500 3575);
DISPLAY INVISIBLE (-1500 3575);
FORCEPROP 1 LAST COMMENT_BODY TRUE
J 0
(-1400 3500);
DISPLAY 1.170213 (-1400 3500);
PAINT GREEN (-1400 3500);
DISPLAY INVISIBLE (-1400 3500);
FORCEPROP 1 LAST OFFPAGE TRUE
J 0
(-1175 3450);
DISPLAY 0.872340 (-1175 3450);
DISPLAY INVISIBLE (-1175 3450);
FORCEADD OFFPAGE..5
(-1500 3775);
FORCEPROP 2 LAST $XR0 213 
J 0
(-1755 3775);
DISPLAY 0.638298 (-1755 3775);
PAINT MONO (-1755 3775);
FORCEPROP 2 LAST PATH I91
J 0
(-1750 3825);
DISPLAY 1.021277 (-1750 3825);
DISPLAY INVISIBLE (-1750 3825);
FORCEPROP 1 LAST COMMENT_BODY TRUE
J 0
(-1400 3700);
DISPLAY 1.170213 (-1400 3700);
PAINT GREEN (-1400 3700);
DISPLAY INVISIBLE (-1400 3700);
FORCEPROP 1 LAST OFFPAGE TRUE
J 0
(-1175 3650);
DISPLAY 0.872340 (-1175 3650);
DISPLAY INVISIBLE (-1175 3650);
FORCEPROP 2 LAST CDS_LIB standard
J 0
(-1500 3775);
DISPLAY INVISIBLE (-1500 3775);
FORCEADD OFFPAGE..1
(-1500 3675);
FORCEPROP 2 LAST $XR0 213 
J 0
(-1752 3675);
DISPLAY 0.638298 (-1752 3675);
PAINT MONO (-1752 3675);
FORCEPROP 2 LAST PATH I92
J 0
(-1750 3725);
DISPLAY 1.021277 (-1750 3725);
DISPLAY INVISIBLE (-1750 3725);
FORCEPROP 1 LAST OFFPAGE TRUE
J 0
(-1175 3550);
DISPLAY 0.872340 (-1175 3550);
DISPLAY INVISIBLE (-1175 3550);
FORCEPROP 1 LAST COMMENT_BODY TRUE
J 0
(-1375 3575);
DISPLAY 1.170213 (-1375 3575);
PAINT GREEN (-1375 3575);
DISPLAY INVISIBLE (-1375 3575);
FORCEPROP 2 LAST CDS_LIB standard
J 0
(-1500 3675);
DISPLAY INVISIBLE (-1500 3675);
FORCEADD OFFPAGE..1
(-1500 3725);
FORCEPROP 2 LAST $XR0 213 
J 0
(-1752 3725);
DISPLAY 0.638298 (-1752 3725);
PAINT MONO (-1752 3725);
FORCEPROP 2 LAST PATH I93
J 0
(-1750 3775);
DISPLAY 1.021277 (-1750 3775);
DISPLAY INVISIBLE (-1750 3775);
FORCEPROP 1 LAST COMMENT_BODY TRUE
J 0
(-1375 3625);
DISPLAY 1.170213 (-1375 3625);
PAINT GREEN (-1375 3625);
DISPLAY INVISIBLE (-1375 3625);
FORCEPROP 1 LAST OFFPAGE TRUE
J 0
(-1175 3600);
DISPLAY 0.872340 (-1175 3600);
DISPLAY INVISIBLE (-1175 3600);
FORCEPROP 2 LAST CDS_LIB standard
J 0
(-1500 3725);
DISPLAY INVISIBLE (-1500 3725);
FORCEADD OFFPAGE..5
(-1500 3825);
FORCEPROP 2 LAST $XR0 213 
J 0
(-1755 3825);
DISPLAY 0.638298 (-1755 3825);
PAINT MONO (-1755 3825);
FORCEPROP 2 LAST PATH I94
J 0
(-1750 3875);
DISPLAY 1.021277 (-1750 3875);
DISPLAY INVISIBLE (-1750 3875);
FORCEPROP 2 LAST CDS_LIB standard
J 0
(-1500 3825);
DISPLAY INVISIBLE (-1500 3825);
FORCEPROP 1 LAST COMMENT_BODY TRUE
J 0
(-1400 3750);
DISPLAY 1.170213 (-1400 3750);
PAINT GREEN (-1400 3750);
DISPLAY INVISIBLE (-1400 3750);
FORCEPROP 1 LAST OFFPAGE TRUE
J 0
(-1175 3700);
DISPLAY 0.872340 (-1175 3700);
DISPLAY INVISIBLE (-1175 3700);
FORCEADD OFFPAGE..1
(1500 -1400);
FORCEPROP 2 LAST $XR0 213 
J 0
(1218 -1400);
DISPLAY 0.638298 (1218 -1400);
PAINT MONO (1218 -1400);
FORCEPROP 2 LAST PATH I95
J 0
(1225 -1350);
DISPLAY 1.021277 (1225 -1350);
DISPLAY INVISIBLE (1225 -1350);
FORCEPROP 2 LAST CDS_LIB standard
J 0
(1500 -1400);
DISPLAY INVISIBLE (1500 -1400);
FORCEPROP 1 LAST COMMENT_BODY TRUE
J 0
(1625 -1500);
DISPLAY 1.170213 (1625 -1500);
PAINT GREEN (1625 -1500);
DISPLAY INVISIBLE (1625 -1500);
FORCEPROP 1 LAST OFFPAGE TRUE
J 0
(1825 -1525);
DISPLAY 0.872340 (1825 -1525);
DISPLAY INVISIBLE (1825 -1525);
FORCEADD OFFPAGE..1
(1500 -1225);
FORCEPROP 2 LAST $XR0 148 
J 0
(1218 -1225);
DISPLAY 0.638298 (1218 -1225);
PAINT MONO (1218 -1225);
FORCEPROP 2 LAST PATH I96
J 0
(1225 -1175);
DISPLAY 1.021277 (1225 -1175);
DISPLAY INVISIBLE (1225 -1175);
FORCEPROP 1 LAST OFFPAGE TRUE
J 0
(1825 -1350);
DISPLAY 0.872340 (1825 -1350);
DISPLAY INVISIBLE (1825 -1350);
FORCEPROP 1 LAST COMMENT_BODY TRUE
J 0
(1625 -1325);
DISPLAY 1.170213 (1625 -1325);
PAINT GREEN (1625 -1325);
DISPLAY INVISIBLE (1625 -1325);
FORCEPROP 2 LAST CDS_LIB standard
J 0
(1500 -1225);
DISPLAY INVISIBLE (1500 -1225);
FORCEADD OFFPAGE..1
(1525 -1050);
FORCEPROP 2 LAST $XR0 148 
J 0
(1273 -1050);
DISPLAY 0.638298 (1273 -1050);
PAINT MONO (1273 -1050);
FORCEPROP 2 LAST PATH I97
J 0
(1275 -1000);
DISPLAY 1.021277 (1275 -1000);
DISPLAY INVISIBLE (1275 -1000);
FORCEPROP 1 LAST OFFPAGE TRUE
J 0
(1850 -1175);
DISPLAY 0.872340 (1850 -1175);
DISPLAY INVISIBLE (1850 -1175);
FORCEPROP 1 LAST COMMENT_BODY TRUE
J 0
(1650 -1150);
DISPLAY 1.170213 (1650 -1150);
PAINT GREEN (1650 -1150);
DISPLAY INVISIBLE (1650 -1150);
FORCEPROP 2 LAST CDS_LIB standard
J 0
(1525 -1050);
DISPLAY INVISIBLE (1525 -1050);
FORCEADD OFFPAGE..1
(1525 -925);
FORCEPROP 2 LAST $XR1 154 
J 0
(1153 -925);
DISPLAY 0.638298 (1153 -925);
PAINT MONO (1153 -925);
FORCEPROP 2 LAST $XR0 153 
J 0
(1273 -925);
DISPLAY 0.638298 (1273 -925);
PAINT MONO (1273 -925);
FORCEPROP 2 LAST PATH I98
J 0
(1275 -875);
DISPLAY 1.021277 (1275 -875);
DISPLAY INVISIBLE (1275 -875);
FORCEPROP 2 LAST CDS_LIB standard
J 0
(1525 -925);
DISPLAY INVISIBLE (1525 -925);
FORCEPROP 1 LAST COMMENT_BODY TRUE
J 0
(1650 -1025);
DISPLAY 1.170213 (1650 -1025);
PAINT GREEN (1650 -1025);
DISPLAY INVISIBLE (1650 -1025);
FORCEPROP 1 LAST OFFPAGE TRUE
J 0
(1850 -1050);
DISPLAY 0.872340 (1850 -1050);
DISPLAY INVISIBLE (1850 -1050);
FORCEADD OFFPAGE..1
(1525 -775);
FORCEPROP 2 LAST $XR1 160 
J 0
(1153 -775);
DISPLAY 0.638298 (1153 -775);
PAINT MONO (1153 -775);
FORCEPROP 2 LAST $XR0 159 
J 0
(1273 -775);
DISPLAY 0.638298 (1273 -775);
PAINT MONO (1273 -775);
FORCEPROP 2 LAST PATH I99
J 0
(1275 -725);
DISPLAY 1.021277 (1275 -725);
DISPLAY INVISIBLE (1275 -725);
FORCEPROP 1 LAST OFFPAGE TRUE
J 0
(1850 -900);
DISPLAY 0.872340 (1850 -900);
DISPLAY INVISIBLE (1850 -900);
FORCEPROP 1 LAST COMMENT_BODY TRUE
J 0
(1650 -875);
DISPLAY 1.170213 (1650 -875);
PAINT GREEN (1650 -875);
DISPLAY INVISIBLE (1650 -875);
FORCEPROP 2 LAST CDS_LIB standard
J 0
(1525 -775);
DISPLAY INVISIBLE (1525 -775);
FORCEADD QUANTA_TITLE_BLOCK_C..1
(5025 -1950);
FORCEPROP 0 LAST CDS_CON_LAST_MODIFIED Fri Aug 25 14:03:30 2023
J 0
(3140 -1935);
PAINT MONO (3140 -1935);
DISPLAY INVISIBLE (3140 -1935);
FORCEPROP 2 LAST CUSTOM_TXT_CDS <XR_PAGE_TITLE>
J 0
(-2865 3300);
DISPLAY 0.638298 (-2865 3300);
PAINT PINK (-2865 3300);
DISPLAY INVISIBLE (-2865 3300);
FORCEPROP 2 LAST CUSTOM_TXT_CDS <CON_LAST_MODIFIED>
J 0
(3140 -1935);
DISPLAY 0.978723 (3140 -1935);
FORCEPROP 2 LAST CUSTOM_TXT_CDS <NAME_2>
J 0
(1850 -1900);
FORCEPROP 2 LAST CUSTOM_TXT_CDS <NAME_1>
J 0
(1850 -1775);
FORCEPROP 2 LAST CUSTOM_TXT_CDS <CON_PAGE_NUM> OF <CON_TOTAL_PAGES>
J 0
(4579 -1932);
DISPLAY 0.978723 (4579 -1932);
FORCEPROP 2 LAST CUSTOM_TXT_CDS <Q_REV>
J 0
(4841 -1847);
DISPLAY 1.212766 (4841 -1847);
FORCEPROP 2 LAST CUSTOM_TXT_CDS <Q_NUMBER>
J 0
(3622 -1847);
DISPLAY 1.212766 (3622 -1847);
FORCEPROP 2 LAST CUSTOM_TXT_CDS <Q_PROJ>
J 0
(2643 -1848);
DISPLAY 1.212766 (2643 -1848);
FORCEPROP 1 LAST Q_TITLE MAIN FPGA / PFR (1/5)
J 0
(-4316 -1924);
DISPLAY 1.957447 (-4316 -1924);
PAINT GREEN (-4316 -1924);
FORCEPROP 1 LAST Q_DEPT 
J 1
(1262 -1901);
DISPLAY 1.957447 (1262 -1901);
PAINT GREEN (1262 -1901);
FORCEPROP 2 LAST CDS_XR_PAGE_TITLE CR-213 : @S9S_MB_2U_LIB.S9S_MB_2U(SCH_1):PAGE213
J 0
(-2865 3300);
DISPLAY 0.638298 (-2865 3300);
PAINT PINK (-2865 3300);
DISPLAY INVISIBLE (-2865 3300);
FORCEPROP 2 LAST CDS_LIB pure_quanta
J 0
(5025 -1950);
PAINT MONO (5025 -1950);
DISPLAY INVISIBLE (5025 -1950);
FORCEPROP 1 LAST CDS_LMAN_SYM_OUTLINE -9475,6775,100,-125
J 0
(5025 -1950);
DISPLAY 0.468085 (5025 -1950);
PAINT GREEN (5025 -1950);
DISPLAY INVISIBLE (5025 -1950);
FORCEPROP 2 LAST PAGE_BORDER TRUE
J 0
(-2865 3300);
DISPLAY 0.638298 (-2865 3300);
PAINT PINK (-2865 3300);
DISPLAY INVISIBLE (-2865 3300);
FORCEPROP 1 LAST COMMENT_BODY TRUE
J 0
(5037 -1963);
DISPLAY 0.978723 (5037 -1963);
PAINT GREEN (5037 -1963);
DISPLAY INVISIBLE (5037 -1963);
FORCEADD DNS..2
(2825 4125);
PAINT RED (2825 4125);
FORCEPROP 2 LAST CDS_LIB mstr_misc
J 0
(2825 4125);
DISPLAY INVISIBLE (2825 4125);
FORCEPROP 1 LAST COMMENT_BODY TRUE
R 1
J 0
(2900 3900);
DISPLAY 0.872340 (2900 3900);
PAINT GREEN (2900 3900);
DISPLAY INVISIBLE (2900 3900);
FORCEADD DNS..2
(2750 4125);
PAINT RED (2750 4125);
FORCEPROP 2 LAST CDS_LIB mstr_misc
J 0
(2750 4125);
DISPLAY INVISIBLE (2750 4125);
FORCEPROP 1 LAST COMMENT_BODY TRUE
R 1
J 0
(2825 3900);
DISPLAY 0.872340 (2825 3900);
PAINT GREEN (2825 3900);
DISPLAY INVISIBLE (2825 3900);
FORCEADD DNS..2
(2750 450);
PAINT RED (2750 450);
FORCEPROP 2 LAST CDS_LIB mstr_misc
J 0
(2750 450);
DISPLAY INVISIBLE (2750 450);
FORCEPROP 1 LAST COMMENT_BODY TRUE
R 1
J 0
(2825 225);
DISPLAY 0.872340 (2825 225);
PAINT GREEN (2825 225);
DISPLAY INVISIBLE (2825 225);
FORCEADD DNS..2
(-3375 825);
PAINT RED (-3375 825);
FORCEPROP 2 LAST CDS_LIB mstr_misc
J 0
(-3375 825);
DISPLAY INVISIBLE (-3375 825);
FORCEPROP 1 LAST COMMENT_BODY TRUE
R 1
J 0
(-3300 600);
DISPLAY 0.872340 (-3300 600);
PAINT GREEN (-3300 600);
DISPLAY INVISIBLE (-3300 600);
WIRE 16 -1 (-3375 950)(-3375 1050);
WIRE 16 -1 (2825 4425)(2825 4350);
WIRE 16 -1 (-2300 2850)(-2300 2725);
WIRE 16 -1 (-2400 1250)(-2400 1150);
WIRE 16 -1 (-1250 1250)(-1250 1150);
WIRE 16 -1 (-1250 275)(-1250 325);
WIRE 16 -1 (-2400 325)(-2400 275);
WIRE 16 -1 (-2125 -250)(-850 -250);
FORCEPROP 0 LAST CDS_PHYS_NET_NAME GPU_NVS_PWR_BRAKE_R_N
J 0
(-2100 -208);
PAINT MONO (-2100 -208);
DISPLAY INVISIBLE (-2100 -208);
FORCEPROP 0 LAST SIG_NAME GPU_NVS_PWR_BRAKE_R_N
J 0
(-1760 -240);
DISPLAY 0.680851 (-1760 -240);
PAINT WHITE (-1760 -240);
WIRE 16 2175 (-3850 -25)(-425 -25);
WIRE 16 2175 (-425 175)(-425 -25);
WIRE 16 2175 (-3850 175)(-3850 -25);
WIRE 16 2175 (-3850 175)(-425 175);
WIRE 16 -1 (-825 25)(-2125 25);
FORCEPROP 2 LAST SIG_NAME SMB_HOST_3V3AUX_PLD_SCL
J 0
(-1785 35);
DISPLAY 0.680851 (-1785 35);
PAINT WHITE (-1785 35);
WIRE 16 -1 (-2125 -375)(-850 -375);
FORCEPROP 0 LAST CDS_PHYS_NET_NAME GPU_FPGA_EROT_RST_R_N
J 0
(-2100 -333);
PAINT MONO (-2100 -333);
DISPLAY INVISIBLE (-2100 -333);
FORCEPROP 0 LAST SIG_NAME GPU_FPGA_EROT_RST_R_N
J 0
(-1760 -365);
DISPLAY 0.680851 (-1760 -365);
PAINT WHITE (-1760 -365);
WIRE 16 -1 (-825 100)(-2125 100);
FORCEPROP 2 LAST SIG_NAME SMB_HOST_3V3AUX_PLD_SDA
J 0
(-1785 110);
DISPLAY 0.680851 (-1785 110);
PAINT WHITE (-1785 110);
WIRE 16 -1 (-3375 475)(-3450 475);
WIRE 16 -1 (-3375 750)(-3375 475);
WIRE 16 -1 (-2650 475)(-3375 475);
FORCEPROP 0 LAST SIG_NAME PWRGD_P5V_AUX
J 0
(-3285 485);
DISPLAY 0.680851 (-3285 485);
PAINT WHITE (-3285 485);
WIRE 16 -1 (-2325 25)(-3375 25);
FORCEPROP 2 LAST SIG_NAME SMB_HOST_3V3AUX_SCL_R4
J 0
(-3360 35);
DISPLAY 0.680851 (-3360 35);
PAINT WHITE (-3360 35);
WIRE 16 -1 (-2325 100)(-3375 100);
FORCEPROP 2 LAST SIG_NAME SMB_HOST_3V3AUX_SDA_R4
J 0
(-3360 110);
DISPLAY 0.680851 (-3360 110);
PAINT WHITE (-3360 110);
WIRE 16 -1 (-2125 -125)(-850 -125);
FORCEPROP 0 LAST CDS_PHYS_NET_NAME GPU_FPGA_THERM_OVERT_ISO_R_N
J 0
(-2100 -83);
PAINT MONO (-2100 -83);
DISPLAY INVISIBLE (-2100 -83);
FORCEPROP 0 LAST SIG_NAME GPU_FPGA_THERM_OVERT_ISO_R_N
J 0
(-1760 -115);
DISPLAY 0.680851 (-1760 -115);
PAINT WHITE (-1760 -115);
WIRE 16 -1 (-3375 -125)(-2325 -125);
FORCEPROP 2 LAST SIG_NAME GPU_FPGA_THERM_OVERT_ISO_N
J 0
(-3260 -115);
DISPLAY 0.553191 (-3260 -115);
PAINT WHITE (-3260 -115);
WIRE 16 -1 (-2125 -500)(-850 -500);
FORCEPROP 0 LAST CDS_PHYS_NET_NAME GPU_BASE_STBY_EN_R
J 0
(-2100 -458);
PAINT MONO (-2100 -458);
DISPLAY INVISIBLE (-2100 -458);
FORCEPROP 0 LAST SIG_NAME GPU_BASE_STBY_EN_R
J 0
(-1760 -490);
DISPLAY 0.680851 (-1760 -490);
PAINT WHITE (-1760 -490);
WIRE 16 -1 (-3375 -250)(-2325 -250);
FORCEPROP 2 LAST SIG_NAME GPU_NVS_PWR_BRAKE_N
J 0
(-3260 -240);
DISPLAY 0.553191 (-3260 -240);
PAINT WHITE (-3260 -240);
WIRE 16 -1 (-3375 -375)(-2325 -375);
FORCEPROP 2 LAST SIG_NAME GPU_FPGA_EROT_RST_N
J 0
(-3260 -365);
DISPLAY 0.553191 (-3260 -365);
PAINT WHITE (-3260 -365);
WIRE 16 -1 (-3375 -500)(-2325 -500);
FORCEPROP 2 LAST SIG_NAME GPU_BASE_STBY_EN
J 0
(-3260 -490);
DISPLAY 0.553191 (-3260 -490);
PAINT WHITE (-3260 -490);
WIRE 16 -1 (-3375 -625)(-2325 -625);
FORCEPROP 2 LAST SIG_NAME GPU_BASE_HMC_READY_ISO
J 0
(-3260 -615);
DISPLAY 0.553191 (-3260 -615);
PAINT WHITE (-3260 -615);
WIRE 16 -1 (-3375 -750)(-2325 -750);
FORCEPROP 2 LAST SIG_NAME GPU_HMC_PRSNT_ISO_N
J 0
(-3260 -740);
DISPLAY 0.553191 (-3260 -740);
PAINT WHITE (-3260 -740);
WIRE 16 -1 (-3375 -875)(-2325 -875);
FORCEPROP 2 LAST SIG_NAME GPU_FPGA_BOOT_EN
J 0
(-3260 -865);
DISPLAY 0.553191 (-3260 -865);
PAINT WHITE (-3260 -865);
WIRE 16 -1 (-2400 725)(-2400 800);
WIRE 16 -1 (-2400 950)(-2400 800);
WIRE 16 -1 (-1600 800)(-2400 800);
FORCEPROP 2 LAST SIG_NAME PWRGD_P5V_AUX_R1
J 0
(-2310 810);
DISPLAY 0.553191 (-2310 810);
PAINT WHITE (-2310 810);
WIRE 16 -1 (-1600 800)(-1600 475);
WIRE 16 -1 (-1600 475)(-1500 475);
WIRE 16 -1 (-1250 725)(-1250 800);
WIRE 16 -1 (-550 800)(-1250 800);
FORCEPROP 2 LAST SIG_NAME PWRGD_P5V_AUX_R2
J 0
(-1125 810);
DISPLAY 0.553191 (-1125 810);
PAINT WHITE (-1125 810);
WIRE 16 -1 (-1250 950)(-1250 800);
WIRE 16 -1 (2750 4250)(2750 4350);
WIRE 16 -1 (2750 4350)(2825 4350);
WIRE 16 -1 (2825 4350)(2825 4250);
WIRE 16 -1 (-1450 1775)(-250 1775);
FORCEPROP 0 LAST CDS_PHYS_NET_NAME GPU_FPGA_EROT_RECOV_R_N
J 0
(-1425 1817);
PAINT MONO (-1425 1817);
DISPLAY INVISIBLE (-1425 1817);
FORCEPROP 0 LAST SIG_NAME GPU_FPGA_EROT_RECOV_R_N
J 0
(-1350 1785);
DISPLAY 0.680851 (-1350 1785);
PAINT WHITE (-1350 1785);
WIRE 16 -1 (-1450 1825)(-250 1825);
FORCEPROP 0 LAST CDS_PHYS_NET_NAME GPU_FPGA_BOOT_EN_R
J 0
(-1425 1867);
PAINT MONO (-1425 1867);
DISPLAY INVISIBLE (-1425 1867);
FORCEPROP 0 LAST SIG_NAME GPU_FPGA_BOOT_EN_R
J 0
(-1350 1835);
DISPLAY 0.680851 (-1350 1835);
PAINT WHITE (-1350 1835);
WIRE 16 -1 (-250 1875)(-1450 1875);
FORCEPROP 2 LAST SIG_NAME SMB_HOST_3V3AUX_PLD_SCL
J 0
(-1360 1885);
DISPLAY 0.680851 (-1360 1885);
PAINT WHITE (-1360 1885);
WIRE 16 -1 (-250 1925)(-1450 1925);
FORCEPROP 2 LAST SIG_NAME SMB_HOST_3V3AUX_PLD_SDA
J 0
(-1360 1935);
DISPLAY 0.680851 (-1360 1935);
PAINT WHITE (-1360 1935);
WIRE 16 -1 (-1450 1625)(-250 1625);
FORCEPROP 0 LAST CDS_PHYS_NET_NAME GPU_WP_HW_CTRL_R_N
J 0
(-1425 1667);
PAINT MONO (-1425 1667);
DISPLAY INVISIBLE (-1425 1667);
FORCEPROP 0 LAST SIG_NAME GPU_WP_HW_CTRL_R_N
J 0
(-1350 1635);
DISPLAY 0.680851 (-1350 1635);
PAINT WHITE (-1350 1635);
WIRE 16 -1 (-1450 1575)(-250 1575);
FORCEPROP 0 LAST CDS_PHYS_NET_NAME GPU_PRSNT_N_ISO_R
J 0
(-1425 1617);
PAINT MONO (-1425 1617);
DISPLAY INVISIBLE (-1425 1617);
FORCEPROP 0 LAST SIG_NAME GPU_PRSNT_N_ISO_R
J 0
(-1350 1585);
DISPLAY 0.680851 (-1350 1585);
PAINT WHITE (-1350 1585);
WIRE 16 -1 (-1450 1525)(-250 1525);
FORCEPROP 0 LAST CDS_PHYS_NET_NAME GPU_FPGA_EROT_FATALERR_ISO_R_N
J 0
(-1425 1567);
PAINT MONO (-1425 1567);
DISPLAY INVISIBLE (-1425 1567);
FORCEPROP 0 LAST SIG_NAME GPU_FPGA_EROT_FATALERR_ISO_R_N
J 0
(-1350 1535);
DISPLAY 0.680851 (-1350 1535);
PAINT WHITE (-1350 1535);
WIRE 16 -1 (-1450 1675)(-250 1675);
FORCEPROP 0 LAST CDS_PHYS_NET_NAME GPU_FPGA_OVERT_ISO_R_N
J 0
(-1425 1717);
PAINT MONO (-1425 1717);
DISPLAY INVISIBLE (-1425 1717);
FORCEPROP 0 LAST SIG_NAME GPU_FPGA_OVERT_ISO_R_N
J 0
(-1350 1685);
DISPLAY 0.680851 (-1350 1685);
PAINT WHITE (-1350 1685);
WIRE 16 -1 (-2125 -1375)(-850 -1375);
FORCEPROP 0 LAST CDS_PHYS_NET_NAME GPU_PRSNT_N_ISO_R
J 0
(-2100 -1333);
PAINT MONO (-2100 -1333);
DISPLAY INVISIBLE (-2100 -1333);
FORCEPROP 0 LAST SIG_NAME GPU_PRSNT_N_ISO_R
J 0
(-1760 -1365);
DISPLAY 0.680851 (-1760 -1365);
PAINT WHITE (-1760 -1365);
WIRE 16 -1 (-1450 3525)(-250 3525);
FORCEPROP 0 LAST CDS_PHYS_NET_NAME BIC_MONITER_ISO_R
J 0
(-1425 3567);
PAINT MONO (-1425 3567);
DISPLAY INVISIBLE (-1425 3567);
FORCEPROP 0 LAST SIG_NAME BIC_MONITER_ISO_R
J 0
(-1360 3535);
DISPLAY 0.680851 (-1360 3535);
PAINT YELLOW (-1360 3535);
WIRE 16 -1 (-1450 3475)(-250 3475);
FORCEPROP 0 LAST CDS_PHYS_NET_NAME BMC_MONITER
J 0
(-1425 3517);
PAINT MONO (-1425 3517);
DISPLAY INVISIBLE (-1425 3517);
FORCEPROP 0 LAST SIG_NAME BMC_MONITER
J 0
(-1360 3485);
DISPLAY 0.680851 (-1360 3485);
PAINT YELLOW (-1360 3485);
WIRE 16 -1 (-250 3275)(-1450 3275);
FORCEPROP 2 LAST SIG_NAME SMB_BMC_GPU_EN
J 0
(-1360 3285);
DISPLAY 0.638298 (-1360 3285);
PAINT WHITE (-1360 3285);
WIRE 16 -1 (-250 3375)(-1450 3375);
FORCEPROP 0 LAST CDS_PHYS_NET_NAME SMB_BMC_SWB_EN
J 0
(-1425 3417);
PAINT MONO (-1425 3417);
DISPLAY INVISIBLE (-1425 3417);
FORCEPROP 0 LAST SIG_NAME SMB_BMC_SWB_EN
J 0
(-1360 3385);
DISPLAY 0.680851 (-1360 3385);
PAINT YELLOW (-1360 3385);
WIRE 16 -1 (-1450 3325)(-250 3325);
FORCEPROP 0 LAST CDS_PHYS_NET_NAME RST_BMC_FROM_SWB_ISO_R_N
J 0
(-1425 3367);
PAINT MONO (-1425 3367);
DISPLAY INVISIBLE (-1425 3367);
FORCEPROP 0 LAST SIG_NAME RST_BMC_FROM_SWB_ISO_R_N
J 0
(-1360 3335);
DISPLAY 0.680851 (-1360 3335);
PAINT YELLOW (-1360 3335);
WIRE 16 -1 (-250 3425)(-1450 3425);
FORCEPROP 0 LAST CDS_PHYS_NET_NAME FM_SWB_BIC_READY_ISO_R_N
J 0
(-1425 3467);
PAINT MONO (-1425 3467);
DISPLAY INVISIBLE (-1425 3467);
FORCEPROP 0 LAST SIG_NAME FM_SWB_BIC_READY_ISO_R_N
J 0
(-1360 3435);
DISPLAY 0.680851 (-1360 3435);
PAINT YELLOW (-1360 3435);
WIRE 16 -1 (-1450 3575)(-250 3575);
FORCEPROP 0 LAST CDS_PHYS_NET_NAME FM_GPU_HSC_EN_R
J 0
(-1425 3617);
PAINT MONO (-1425 3617);
DISPLAY INVISIBLE (-1425 3617);
FORCEPROP 0 LAST SIG_NAME FM_GPU_HSC_EN_R
J 0
(-1360 3585);
DISPLAY 0.680851 (-1360 3585);
PAINT YELLOW (-1360 3585);
WIRE 16 -1 (-1450 3675)(-250 3675);
FORCEPROP 0 LAST CDS_PHYS_NET_NAME FM_GPU_PWRGD_ISO_R
J 0
(-1425 3717);
PAINT MONO (-1425 3717);
DISPLAY INVISIBLE (-1425 3717);
FORCEPROP 0 LAST SIG_NAME FM_GPU_PWRGD_ISO_R
J 0
(-1360 3685);
DISPLAY 0.680851 (-1360 3685);
PAINT YELLOW (-1360 3685);
WIRE 16 -1 (-1450 3775)(-250 3775);
FORCEPROP 0 LAST CDS_PHYS_NET_NAME FM_GPU_PWR_EN
J 0
(-1425 3817);
PAINT MONO (-1425 3817);
DISPLAY INVISIBLE (-1425 3817);
FORCEPROP 0 LAST SIG_NAME FM_GPU_PWR_EN
J 0
(-1360 3785);
DISPLAY 0.680851 (-1360 3785);
PAINT YELLOW (-1360 3785);
WIRE 16 -1 (-1450 3825)(-250 3825);
FORCEPROP 0 LAST CDS_PHYS_NET_NAME FM_SWB_PWR_EN
J 0
(-1425 3867);
PAINT MONO (-1425 3867);
DISPLAY INVISIBLE (-1425 3867);
FORCEPROP 0 LAST SIG_NAME FM_SWB_PWR_EN
J 0
(-1360 3835);
DISPLAY 0.680851 (-1360 3835);
PAINT YELLOW (-1360 3835);
WIRE 16 -1 (-1450 3225)(-250 3225);
FORCEPROP 0 LAST CDS_PHYS_NET_NAME FM_PCH_PRSNT_N
J 0
(-1425 3267);
PAINT MONO (-1425 3267);
DISPLAY INVISIBLE (-1425 3267);
FORCEPROP 0 LAST SIG_NAME FM_PCH_PRSNT_N
J 0
(-1350 3235);
DISPLAY 0.680851 (-1350 3235);
PAINT WHITE (-1350 3235);
WIRE 16 -1 (-1450 3175)(-250 3175);
FORCEPROP 0 LAST CDS_PHYS_NET_NAME FM_TPM_PRSNT_R_N
J 0
(-1425 3217);
PAINT MONO (-1425 3217);
DISPLAY INVISIBLE (-1425 3217);
FORCEPROP 0 LAST SIG_NAME FM_TPM_PRSNT_R_N
J 0
(-1350 3185);
DISPLAY 0.680851 (-1350 3185);
PAINT WHITE (-1350 3185);
WIRE 16 -1 (-1450 3125)(-250 3125);
FORCEPROP 0 LAST CDS_PHYS_NET_NAME VIRTUAL_RESEAT_FPGA_R_N
J 0
(-1425 3167);
PAINT MONO (-1425 3167);
DISPLAY INVISIBLE (-1425 3167);
FORCEPROP 0 LAST SIG_NAME VIRTUAL_RESEAT_FPGA_R_N
J 0
(-1350 3135);
DISPLAY 0.680851 (-1350 3135);
PAINT WHITE (-1350 3135);
WIRE 16 -1 (-1450 3075)(-250 3075);
FORCEPROP 0 LAST CDS_PHYS_NET_NAME FM_BMC_SUSACK_R_N
J 0
(-1425 3117);
PAINT MONO (-1425 3117);
DISPLAY INVISIBLE (-1425 3117);
FORCEPROP 0 LAST SIG_NAME FM_BMC_SUSACK_R_N
J 0
(-1350 3085);
DISPLAY 0.680851 (-1350 3085);
PAINT WHITE (-1350 3085);
WIRE 16 -1 (-1450 3625)(-250 3625);
FORCEPROP 0 LAST CDS_PHYS_NET_NAME FM_FAN_PWR_EN
J 0
(-1425 3667);
PAINT MONO (-1425 3667);
DISPLAY INVISIBLE (-1425 3667);
FORCEPROP 0 LAST SIG_NAME FM_FAN_PWR_EN
J 0
(-1360 3635);
DISPLAY 0.680851 (-1360 3635);
PAINT YELLOW (-1360 3635);
WIRE 16 -1 (-1450 3725)(-250 3725);
FORCEPROP 0 LAST CDS_PHYS_NET_NAME FM_SWB_PWRGD_ISO_R
J 0
(-1425 3767);
PAINT MONO (-1425 3767);
DISPLAY INVISIBLE (-1425 3767);
FORCEPROP 0 LAST SIG_NAME FM_SWB_PWRGD_ISO_R
J 0
(-1360 3735);
DISPLAY 0.680851 (-1360 3735);
PAINT YELLOW (-1360 3735);
WIRE 16 -1 (1550 -275)(2625 -275);
FORCEPROP 0 LAST CDS_PHYS_NET_NAME FM_SWB_PWRGD_ISO
J 0
(1575 -233);
PAINT MONO (1575 -233);
DISPLAY INVISIBLE (1575 -233);
FORCEPROP 0 LAST SIG_NAME FM_SWB_PWRGD_ISO
J 0
(1665 -265);
DISPLAY 0.680851 (1665 -265);
PAINT WHITE (1665 -265);
WIRE 16 -1 (2625 -1225)(1550 -1225);
FORCEPROP 2 LAST SIG_NAME RST_BMC_FROM_SWB_ISO_N
J 0
(1640 -1215);
DISPLAY 0.638298 (1640 -1215);
PAINT WHITE (1640 -1215);
WIRE 16 -1 (2625 -1400)(1550 -1400);
FORCEPROP 2 LAST SIG_NAME FM_GPU_HSC_EN_R
J 0
(1640 -1390);
DISPLAY 0.638298 (1640 -1390);
PAINT WHITE (1640 -1390);
WIRE 16 -1 (1575 -775)(2625 -775);
FORCEPROP 2 LAST SIG_NAME FM_OCP_V3_2_PWR_GOOD
J 0
(1690 -765);
DISPLAY 0.553191 (1690 -765);
PAINT WHITE (1690 -765);
WIRE 16 -1 (1550 -525)(2625 -525);
FORCEPROP 0 LAST CDS_PHYS_NET_NAME FM_SWB_BIC_READY_ISO_N
J 0
(1575 -483);
PAINT MONO (1575 -483);
DISPLAY INVISIBLE (1575 -483);
FORCEPROP 0 LAST SIG_NAME FM_SWB_BIC_READY_ISO_N
J 0
(1665 -515);
DISPLAY 0.680851 (1665 -515);
PAINT WHITE (1665 -515);
WIRE 16 -1 (1550 -150)(2625 -150);
FORCEPROP 0 LAST CDS_PHYS_NET_NAME FM_GPU_PWR_EN
J 0
(1575 -108);
PAINT MONO (1575 -108);
DISPLAY INVISIBLE (1575 -108);
FORCEPROP 0 LAST SIG_NAME FM_GPU_PWR_EN
J 0
(1665 -140);
DISPLAY 0.680851 (1665 -140);
PAINT WHITE (1665 -140);
WIRE 16 -1 (1575 -1050)(2625 -1050);
FORCEPROP 2 LAST SIG_NAME GPU_FPGA_READY_ISO
J 0
(1690 -1040);
DISPLAY 0.553191 (1690 -1040);
PAINT WHITE (1690 -1040);
WIRE 16 -1 (1575 -925)(2625 -925);
FORCEPROP 2 LAST SIG_NAME FM_OCP_SFF_PWR_GOOD
J 0
(1690 -915);
DISPLAY 0.553191 (1690 -915);
PAINT WHITE (1690 -915);
WIRE 16 -1 (2625 -400)(1550 -400);
FORCEPROP 2 LAST SIG_NAME FM_GPU_PWRGD_ISO
J 0
(1655 -390);
DISPLAY 0.638298 (1655 -390);
PAINT WHITE (1655 -390);
WIRE 16 -1 (2825 -1225)(3900 -1225);
FORCEPROP 0 LAST CDS_PHYS_NET_NAME RST_BMC_FROM_SWB_ISO_R_N
J 0
(3140 -1185);
PAINT MONO (3140 -1185);
DISPLAY INVISIBLE (3140 -1185);
FORCEPROP 2 LAST SIG_NAME RST_BMC_FROM_SWB_ISO_R_N
J 0
(3190 -1215);
DISPLAY 0.638298 (3190 -1215);
PAINT WHITE (3190 -1215);
WIRE 16 -1 (2825 -1400)(3900 -1400);
FORCEPROP 0 LAST CDS_PHYS_NET_NAME FM_GPU_HSC_EN
J 0
(3140 -1360);
PAINT MONO (3140 -1360);
DISPLAY INVISIBLE (3140 -1360);
FORCEPROP 2 LAST SIG_NAME FM_GPU_HSC_EN
J 0
(3190 -1390);
DISPLAY 0.638298 (3190 -1390);
PAINT WHITE (3190 -1390);
WIRE 16 -1 (2825 -1050)(3900 -1050);
FORCEPROP 0 LAST CDS_PHYS_NET_NAME GPU_FPGA_READY_ISO_R
J 0
(2850 -1008);
PAINT MONO (2850 -1008);
DISPLAY INVISIBLE (2850 -1008);
FORCEPROP 0 LAST SIG_NAME GPU_FPGA_READY_ISO_R
J 0
(3190 -1040);
DISPLAY 0.680851 (3190 -1040);
PAINT WHITE (3190 -1040);
WIRE 16 -1 (2825 -275)(3900 -275);
FORCEPROP 0 LAST CDS_PHYS_NET_NAME FM_SWB_PWRGD_ISO_R
J 0
(3140 -235);
PAINT MONO (3140 -235);
DISPLAY INVISIBLE (3140 -235);
FORCEPROP 2 LAST SIG_NAME FM_SWB_PWRGD_ISO_R
J 0
(3165 -265);
DISPLAY 0.638298 (3165 -265);
PAINT WHITE (3165 -265);
WIRE 16 -1 (2825 -525)(3900 -525);
FORCEPROP 0 LAST CDS_PHYS_NET_NAME FM_SWB_BIC_READY_ISO_R_N
J 0
(3140 -485);
PAINT MONO (3140 -485);
DISPLAY INVISIBLE (3140 -485);
FORCEPROP 2 LAST SIG_NAME FM_SWB_BIC_READY_ISO_R_N
J 0
(3165 -515);
DISPLAY 0.638298 (3165 -515);
PAINT WHITE (3165 -515);
WIRE 16 -1 (2825 -925)(3900 -925);
FORCEPROP 0 LAST CDS_PHYS_NET_NAME FM_OCP_SFF_PWR_GOOD_R
J 0
(2850 -883);
PAINT MONO (2850 -883);
DISPLAY INVISIBLE (2850 -883);
FORCEPROP 0 LAST SIG_NAME FM_OCP_SFF_PWR_GOOD_R
J 0
(3190 -915);
DISPLAY 0.680851 (3190 -915);
PAINT WHITE (3190 -915);
WIRE 16 -1 (2825 -400)(3900 -400);
FORCEPROP 0 LAST CDS_PHYS_NET_NAME FM_GPU_PWRGD_ISO_R
J 0
(3140 -360);
PAINT MONO (3140 -360);
DISPLAY INVISIBLE (3140 -360);
FORCEPROP 2 LAST SIG_NAME FM_GPU_PWRGD_ISO_R
J 0
(3165 -390);
DISPLAY 0.638298 (3165 -390);
PAINT WHITE (3165 -390);
WIRE 16 -1 (2825 -150)(3900 -150);
FORCEPROP 0 LAST CDS_PHYS_NET_NAME FM_GPU_PWR_EN_R
J 0
(3140 -110);
PAINT MONO (3140 -110);
DISPLAY INVISIBLE (3140 -110);
FORCEPROP 2 LAST SIG_NAME FM_GPU_PWR_EN_R
J 0
(3165 -140);
DISPLAY 0.638298 (3165 -140);
PAINT WHITE (3165 -140);
WIRE 16 -1 (2825 -650)(3900 -650);
FORCEPROP 0 LAST CDS_PHYS_NET_NAME IRQ_HSC_FAULT_R1_N
J 0
(3140 -610);
PAINT MONO (3140 -610);
DISPLAY INVISIBLE (3140 -610);
FORCEPROP 2 LAST SIG_NAME IRQ_HSC_FAULT_R1_N
J 0
(3165 -640);
DISPLAY 0.638298 (3165 -640);
PAINT WHITE (3165 -640);
WIRE 16 -1 (2825 -775)(3900 -775);
FORCEPROP 0 LAST CDS_PHYS_NET_NAME FM_OCP_V3_2_PWR_GOOD_R
J 0
(2850 -733);
PAINT MONO (2850 -733);
DISPLAY INVISIBLE (2850 -733);
FORCEPROP 0 LAST SIG_NAME FM_OCP_V3_2_PWR_GOOD_R
J 0
(3190 -765);
DISPLAY 0.680851 (3190 -765);
PAINT WHITE (3190 -765);
WIRE 16 -1 (1550 950)(2625 950);
FORCEPROP 2 LAST SIG_NAME JTAG_BMC_SW_OE
J 0
(1665 960);
DISPLAY 0.680851 (1665 960);
PAINT WHITE (1665 960);
WIRE 16 -1 (1550 825)(2625 825);
FORCEPROP 2 LAST SIG_NAME OCP_SFF_CLK_OE_R_N
J 0
(1640 835);
DISPLAY 0.680851 (1640 835);
PAINT WHITE (1640 835);
WIRE 16 -1 (1550 700)(2625 700);
FORCEPROP 0 LAST CDS_PHYS_NET_NAME FM_TPM_PRSNT_R_N
J 0
(1575 742);
PAINT MONO (1575 742);
DISPLAY INVISIBLE (1575 742);
FORCEPROP 0 LAST SIG_NAME FM_TPM_PRSNT_R_N
J 0
(1665 710);
DISPLAY 0.680851 (1665 710);
PAINT WHITE (1665 710);
WIRE 16 -1 (1550 575)(2625 575);
FORCEPROP 0 LAST CDS_PHYS_NET_NAME VIRTUAL_RESEAT_FPGA_R_N
J 0
(1575 617);
PAINT MONO (1575 617);
DISPLAY INVISIBLE (1575 617);
FORCEPROP 0 LAST SIG_NAME VIRTUAL_RESEAT_FPGA_R_N
J 0
(1665 585);
DISPLAY 0.680851 (1665 585);
PAINT WHITE (1665 585);
WIRE 16 -1 (1550 450)(2625 450);
FORCEPROP 0 LAST CDS_PHYS_NET_NAME FM_BMC_SUSACK_R_N
J 0
(1575 492);
PAINT MONO (1575 492);
DISPLAY INVISIBLE (1575 492);
FORCEPROP 0 LAST SIG_NAME FM_BMC_SUSACK_R_N
J 0
(1665 460);
DISPLAY 0.680851 (1665 460);
PAINT WHITE (1665 460);
WIRE 16 -1 (1550 300)(2625 300);
FORCEPROP 0 LAST CDS_PHYS_NET_NAME BMC_MONITER
J 0
(1575 342);
PAINT MONO (1575 342);
DISPLAY INVISIBLE (1575 342);
FORCEPROP 0 LAST SIG_NAME BMC_MONITER
J 0
(1650 310);
DISPLAY 0.680851 (1650 310);
PAINT WHITE (1650 310);
WIRE 16 -1 (1550 125)(2625 125);
FORCEPROP 0 LAST CDS_PHYS_NET_NAME BIC_MONITER_ISO
J 0
(1575 167);
PAINT MONO (1575 167);
DISPLAY INVISIBLE (1575 167);
FORCEPROP 0 LAST SIG_NAME BIC_MONITER_ISO
J 0
(1650 135);
DISPLAY 0.680851 (1650 135);
PAINT WHITE (1650 135);
WIRE 16 -1 (1550 -25)(2625 -25);
FORCEPROP 0 LAST CDS_PHYS_NET_NAME FM_SWB_PWR_EN
J 0
(1575 17);
PAINT MONO (1575 17);
DISPLAY INVISIBLE (1575 17);
FORCEPROP 0 LAST SIG_NAME FM_SWB_PWR_EN
J 0
(1665 -15);
DISPLAY 0.680851 (1665 -15);
PAINT WHITE (1665 -15);
WIRE 16 -1 (1850 1675)(2900 1675);
FORCEPROP 0 LAST CDS_PHYS_NET_NAME NC_FPGA_PT43D
J 0
(1875 1717);
PAINT MONO (1875 1717);
DISPLAY INVISIBLE (1875 1717);
FORCEPROP 0 LAST SIG_NAME NC_FPGA_PT43D
J 0
(2015 1685);
DISPLAY 0.680851 (2015 1685);
PAINT WHITE (2015 1685);
WIRE 16 -1 (1850 1575)(2900 1575);
FORCEPROP 0 LAST CDS_PHYS_NET_NAME NC_FPGA_PT44A
J 0
(1875 1617);
PAINT MONO (1875 1617);
DISPLAY INVISIBLE (1875 1617);
FORCEPROP 0 LAST SIG_NAME NC_FPGA_PT44A
J 0
(2015 1585);
DISPLAY 0.680851 (2015 1585);
PAINT WHITE (2015 1585);
WIRE 16 -1 (1850 1725)(2900 1725);
FORCEPROP 0 LAST CDS_PHYS_NET_NAME NC_FPGA_PT43C
J 0
(1875 1767);
PAINT MONO (1875 1767);
DISPLAY INVISIBLE (1875 1767);
FORCEPROP 0 LAST SIG_NAME NC_FPGA_PT43C
J 0
(2015 1735);
DISPLAY 0.680851 (2015 1735);
PAINT WHITE (2015 1735);
WIRE 16 -1 (1850 1925)(2900 1925);
FORCEPROP 0 LAST CDS_PHYS_NET_NAME NC_FPGA_PT42D
J 0
(1875 1967);
PAINT MONO (1875 1967);
DISPLAY INVISIBLE (1875 1967);
FORCEPROP 0 LAST SIG_NAME NC_FPGA_PT42D
J 0
(2015 1935);
DISPLAY 0.680851 (2015 1935);
PAINT WHITE (2015 1935);
WIRE 16 -1 (1850 1975)(2900 1975);
FORCEPROP 0 LAST CDS_PHYS_NET_NAME RST_SRST_PLD_BMC_R_N
J 0
(1875 2017);
PAINT MONO (1875 2017);
DISPLAY INVISIBLE (1875 2017);
FORCEPROP 0 LAST SIG_NAME RST_SRST_PLD_BMC_R_N
J 0
(2015 1985);
DISPLAY 0.680851 (2015 1985);
PAINT WHITE (2015 1985);
WIRE 16 -1 (1850 1825)(2900 1825);
FORCEPROP 0 LAST CDS_PHYS_NET_NAME NC_FPGA_PT43A
J 0
(1875 1867);
PAINT MONO (1875 1867);
DISPLAY INVISIBLE (1875 1867);
FORCEPROP 0 LAST SIG_NAME NC_FPGA_PT43A
J 0
(2015 1835);
DISPLAY 0.680851 (2015 1835);
PAINT WHITE (2015 1835);
WIRE 16 -1 (1850 1775)(2900 1775);
FORCEPROP 0 LAST CDS_PHYS_NET_NAME NC_FPGA_PT43B
J 0
(1875 1817);
PAINT MONO (1875 1817);
DISPLAY INVISIBLE (1875 1817);
FORCEPROP 0 LAST SIG_NAME NC_FPGA_PT43B
J 0
(2015 1785);
DISPLAY 0.680851 (2015 1785);
PAINT WHITE (2015 1785);
WIRE 16 -1 (1850 1525)(2900 1525);
FORCEPROP 0 LAST CDS_PHYS_NET_NAME NC_FPGA_PT44B
J 0
(1875 1567);
PAINT MONO (1875 1567);
DISPLAY INVISIBLE (1875 1567);
FORCEPROP 0 LAST SIG_NAME NC_FPGA_PT44B
J 0
(2015 1535);
DISPLAY 0.680851 (2015 1535);
PAINT WHITE (2015 1535);
WIRE 16 -1 (2750 3775)(1850 3775);
WIRE 16 -1 (2750 4050)(2750 3775);
FORCEPROP 0 LAST SIG_NAME SMB_1_PLD_3V3AUX_SCL_R1
J 0
(2015 3785);
DISPLAY 0.680851 (2015 3785);
PAINT WHITE (2015 3785);
WIRE 16 -1 (2750 3775)(2900 3775);
FORCEPROP 0 LAST CDS_PHYS_NET_NAME SMB_1_PLD_3V3AUX_SCL_R1
J 0
(3275 3817);
PAINT MONO (3275 3817);
DISPLAY INVISIBLE (3275 3817);
WIRE 16 -1 (1850 2075)(2900 2075);
FORCEPROP 0 LAST CDS_PHYS_NET_NAME P12V_HSC_TEMP_ALERT_R_N
J 0
(1875 2117);
PAINT MONO (1875 2117);
DISPLAY INVISIBLE (1875 2117);
FORCEPROP 0 LAST SIG_NAME P12V_HSC_TEMP_ALERT_R_N
J 0
(2015 2085);
DISPLAY 0.680851 (2015 2085);
PAINT WHITE (2015 2085);
WIRE 16 -1 (1850 2025)(2900 2025);
FORCEPROP 0 LAST CDS_PHYS_NET_NAME P12V_HSC_T_CRIT_R_N
J 0
(1875 2067);
PAINT MONO (1875 2067);
DISPLAY INVISIBLE (1875 2067);
FORCEPROP 0 LAST SIG_NAME P12V_HSC_T_CRIT_R_N
J 0
(2015 2035);
DISPLAY 0.680851 (2015 2035);
PAINT WHITE (2015 2035);
WIRE 16 -1 (1850 2575)(2900 2575);
FORCEPROP 0 LAST CDS_PHYS_NET_NAME SGPIO_OCP_SFF_LD_N
J 0
(1875 2617);
PAINT MONO (1875 2617);
DISPLAY INVISIBLE (1875 2617);
FORCEPROP 0 LAST SIG_NAME SGPIO_OCP_SFF_LD_N
J 0
(2015 2585);
DISPLAY 0.680851 (2015 2585);
PAINT WHITE (2015 2585);
WIRE 16 -1 (1850 2525)(2900 2525);
FORCEPROP 0 LAST CDS_PHYS_NET_NAME SGPIO_OCP_V3_2_DATAOUT
J 0
(1875 2567);
PAINT MONO (1875 2567);
DISPLAY INVISIBLE (1875 2567);
FORCEPROP 0 LAST SIG_NAME SGPIO_OCP_V3_2_DATAOUT
J 0
(2015 2535);
DISPLAY 0.680851 (2015 2535);
PAINT WHITE (2015 2535);
WIRE 16 -1 (1850 2475)(2900 2475);
FORCEPROP 0 LAST CDS_PHYS_NET_NAME SGPIO_OCP_V3_2_CLK
J 0
(1875 2517);
PAINT MONO (1875 2517);
DISPLAY INVISIBLE (1875 2517);
FORCEPROP 0 LAST SIG_NAME SGPIO_OCP_V3_2_CLK
J 0
(2015 2485);
DISPLAY 0.680851 (2015 2485);
PAINT WHITE (2015 2485);
WIRE 16 -1 (1850 2275)(2900 2275);
FORCEPROP 0 LAST CDS_PHYS_NET_NAME PU_MAIN_FPGA_CONFIG_DONE
J 0
(1875 2317);
PAINT MONO (1875 2317);
DISPLAY INVISIBLE (1875 2317);
FORCEPROP 0 LAST SIG_NAME PU_MAIN_FPGA_CONFIG_DONE
J 0
(2015 2285);
DISPLAY 0.680851 (2015 2285);
PAINT WHITE (2015 2285);
WIRE 16 -1 (1850 2225)(2900 2225);
FORCEPROP 2 LAST SIG_NAME JTAG_BMC_SW_PLD_OE
J 0
(2015 2235);
DISPLAY 0.680851 (2015 2235);
PAINT WHITE (2015 2235);
WIRE 16 -1 (1850 2175)(2900 2175);
FORCEPROP 0 LAST CDS_PHYS_NET_NAME NC_FPGA_PT41D
J 0
(1875 2217);
PAINT MONO (1875 2217);
DISPLAY INVISIBLE (1875 2217);
FORCEPROP 0 LAST SIG_NAME NC_FPGA_PT41D
J 0
(2015 2185);
DISPLAY 0.680851 (2015 2185);
PAINT WHITE (2015 2185);
WIRE 16 -1 (1850 2375)(2900 2375);
FORCEPROP 0 LAST CDS_PHYS_NET_NAME SGPIO_OCP_V3_2_LD_N
J 0
(1875 2417);
PAINT MONO (1875 2417);
DISPLAY INVISIBLE (1875 2417);
FORCEPROP 0 LAST SIG_NAME SGPIO_OCP_V3_2_LD_N
J 0
(2015 2385);
DISPLAY 0.680851 (2015 2385);
PAINT WHITE (2015 2385);
WIRE 16 -1 (1850 2425)(2900 2425);
FORCEPROP 0 LAST CDS_PHYS_NET_NAME SGPIO_OCP_V3_2_DATAIN
J 0
(1875 2467);
PAINT MONO (1875 2467);
DISPLAY INVISIBLE (1875 2467);
FORCEPROP 0 LAST SIG_NAME SGPIO_OCP_V3_2_DATAIN
J 0
(2015 2435);
DISPLAY 0.680851 (2015 2435);
PAINT WHITE (2015 2435);
WIRE 16 -1 (1850 2325)(2900 2325);
FORCEPROP 0 LAST CDS_PHYS_NET_NAME GPU_FPGA_READY_ISO_R
J 0
(1875 2367);
PAINT MONO (1875 2367);
DISPLAY INVISIBLE (1875 2367);
FORCEPROP 0 LAST SIG_NAME GPU_FPGA_READY_ISO_R
J 0
(2015 2335);
DISPLAY 0.680851 (2015 2335);
PAINT WHITE (2015 2335);
WIRE 16 -1 (1850 3225)(2900 3225);
FORCEPROP 0 LAST CDS_PHYS_NET_NAME FM_NCSI_OCP_V3_2_R_OE
J 0
(1875 3267);
PAINT MONO (1875 3267);
DISPLAY INVISIBLE (1875 3267);
FORCEPROP 0 LAST SIG_NAME FM_NCSI_OCP_V3_2_R_OE
J 0
(2015 3235);
DISPLAY 0.680851 (2015 3235);
WIRE 16 -1 (1850 3075)(2900 3075);
FORCEPROP 0 LAST CDS_PHYS_NET_NAME SGPIO_BMC_DIN_R
J 0
(1875 3117);
PAINT MONO (1875 3117);
DISPLAY INVISIBLE (1875 3117);
FORCEPROP 0 LAST SIG_NAME SGPIO_BMC_DIN_R
J 0
(2015 3085);
DISPLAY 0.680851 (2015 3085);
PAINT WHITE (2015 3085);
WIRE 16 -1 (1850 3025)(2900 3025);
FORCEPROP 0 LAST CDS_PHYS_NET_NAME SGPIO_BMC_LD_N
J 0
(1875 3067);
PAINT MONO (1875 3067);
DISPLAY INVISIBLE (1875 3067);
FORCEPROP 0 LAST SIG_NAME SGPIO_BMC_LD_N
J 0
(2015 3035);
DISPLAY 0.680851 (2015 3035);
PAINT WHITE (2015 3035);
WIRE 16 -1 (1850 3125)(2900 3125);
FORCEPROP 0 LAST CDS_PHYS_NET_NAME SGPIO_BMC_CLK
J 0
(1875 3167);
PAINT MONO (1875 3167);
DISPLAY INVISIBLE (1875 3167);
FORCEPROP 0 LAST SIG_NAME SGPIO_BMC_CLK
J 0
(2015 3135);
DISPLAY 0.680851 (2015 3135);
PAINT WHITE (2015 3135);
WIRE 16 -1 (1850 3175)(2900 3175);
FORCEPROP 0 LAST CDS_PHYS_NET_NAME SGPIO_BMC_DOUT
J 0
(1875 3217);
PAINT MONO (1875 3217);
DISPLAY INVISIBLE (1875 3217);
FORCEPROP 0 LAST SIG_NAME SGPIO_BMC_DOUT
J 0
(2015 3185);
DISPLAY 0.680851 (2015 3185);
PAINT WHITE (2015 3185);
WIRE 16 -1 (1850 2825)(2900 2825);
FORCEPROP 0 LAST CDS_PHYS_NET_NAME SGPIO_DEBUG_PLD_DIN
J 0
(1875 2867);
PAINT MONO (1875 2867);
DISPLAY INVISIBLE (1875 2867);
FORCEPROP 0 LAST SIG_NAME SGPIO_DEBUG_PLD_DIN
J 0
(2015 2835);
DISPLAY 0.680851 (2015 2835);
PAINT WHITE (2015 2835);
WIRE 16 -1 (1850 2775)(2900 2775);
FORCEPROP 0 LAST CDS_PHYS_NET_NAME SGPIO_DEBUG_PLD_LD_N
J 0
(1875 2817);
PAINT MONO (1875 2817);
DISPLAY INVISIBLE (1875 2817);
FORCEPROP 0 LAST SIG_NAME SGPIO_DEBUG_PLD_LD_N
J 0
(2015 2785);
DISPLAY 0.680851 (2015 2785);
PAINT WHITE (2015 2785);
WIRE 16 -1 (1850 2725)(2900 2725);
FORCEPROP 0 LAST CDS_PHYS_NET_NAME SGPIO_OCP_SFF_DATAOUT
J 0
(1875 2767);
PAINT MONO (1875 2767);
DISPLAY INVISIBLE (1875 2767);
FORCEPROP 0 LAST SIG_NAME SGPIO_OCP_SFF_DATAOUT
J 0
(2015 2735);
DISPLAY 0.680851 (2015 2735);
PAINT WHITE (2015 2735);
WIRE 16 -1 (1850 2675)(2900 2675);
FORCEPROP 0 LAST CDS_PHYS_NET_NAME SGPIO_OCP_SFF_CLK
J 0
(1875 2717);
PAINT MONO (1875 2717);
DISPLAY INVISIBLE (1875 2717);
FORCEPROP 0 LAST SIG_NAME SGPIO_OCP_SFF_CLK
J 0
(2015 2685);
DISPLAY 0.680851 (2015 2685);
PAINT WHITE (2015 2685);
WIRE 16 -1 (1850 2625)(2900 2625);
FORCEPROP 0 LAST CDS_PHYS_NET_NAME SGPIO_OCP_SFF_DATAIN
J 0
(1875 2667);
PAINT MONO (1875 2667);
DISPLAY INVISIBLE (1875 2667);
FORCEPROP 0 LAST SIG_NAME SGPIO_OCP_SFF_DATAIN
J 0
(2015 2635);
DISPLAY 0.680851 (2015 2635);
PAINT WHITE (2015 2635);
WIRE 16 -1 (1850 2925)(2900 2925);
FORCEPROP 0 LAST CDS_PHYS_NET_NAME SGPIO_DEBUG_PLD_DOUT
J 0
(1875 2967);
PAINT MONO (1875 2967);
DISPLAY INVISIBLE (1875 2967);
FORCEPROP 0 LAST SIG_NAME SGPIO_DEBUG_PLD_DOUT
J 0
(2015 2935);
DISPLAY 0.680851 (2015 2935);
PAINT WHITE (2015 2935);
WIRE 16 -1 (1850 2875)(2900 2875);
FORCEPROP 0 LAST CDS_PHYS_NET_NAME SGPIO_DEBUG_PLD_CLK
J 0
(1875 2917);
PAINT MONO (1875 2917);
DISPLAY INVISIBLE (1875 2917);
FORCEPROP 0 LAST SIG_NAME SGPIO_DEBUG_PLD_CLK
J 0
(2015 2885);
DISPLAY 0.680851 (2015 2885);
PAINT WHITE (2015 2885);
WIRE 16 -1 (1850 3275)(2900 3275);
FORCEPROP 0 LAST CDS_PHYS_NET_NAME PWRGD_PVPP_HBM_CPU1
J 0
(1875 3317);
PAINT MONO (1875 3317);
DISPLAY INVISIBLE (1875 3317);
FORCEPROP 0 LAST SIG_NAME PWRGD_PVPP_HBM_CPU1
J 0
(2015 3285);
DISPLAY 0.680851 (2015 3285);
PAINT WHITE (2015 3285);
WIRE 16 -1 (1850 3825)(2900 3825);
FORCEPROP 0 LAST CDS_PHYS_NET_NAME PWRGD_P3V3
J 0
(1875 3867);
PAINT MONO (1875 3867);
DISPLAY INVISIBLE (1875 3867);
FORCEPROP 0 LAST SIG_NAME PWRGD_P3V3
J 0
(2015 3835);
DISPLAY 0.680851 (2015 3835);
PAINT WHITE (2015 3835);
WIRE 16 -1 (1850 3875)(2900 3875);
FORCEPROP 0 LAST CDS_PHYS_NET_NAME PWRGD_P5V_AUX_R2
J 0
(1875 3917);
PAINT MONO (1875 3917);
DISPLAY INVISIBLE (1875 3917);
FORCEPROP 0 LAST SIG_NAME PWRGD_P5V_AUX_R2
J 0
(2015 3885);
DISPLAY 0.680851 (2015 3885);
PAINT WHITE (2015 3885);
WIRE 16 -1 (2900 3725)(2825 3725);
FORCEPROP 0 LAST CDS_PHYS_NET_NAME SMB_1_PLD_3V3AUX_SDA_R1
J 0
(2350 3767);
PAINT MONO (2350 3767);
DISPLAY INVISIBLE (2350 3767);
FORCEPROP 0 LAST SIG_NAME SMB_1_PLD_3V3AUX_SDA_R1
J 0
(2015 3735);
DISPLAY 0.680851 (2015 3735);
PAINT WHITE (2015 3735);
WIRE 16 -1 (2825 4050)(2825 3725);
WIRE 16 -1 (1850 3725)(2825 3725);
WIRE 16 2175 (1150 875)(4275 875);
WIRE 16 2175 (4275 1075)(4275 875);
WIRE 16 2175 (1150 1075)(1150 875);
WIRE 16 2175 (1150 1075)(4275 1075);
WIRE 16 -1 (2825 950)(3900 950);
FORCEPROP 2 LAST SIG_NAME JTAG_BMC_SW_PLD_OE
J 0
(3190 960);
DISPLAY 0.680851 (3190 960);
PAINT WHITE (3190 960);
WIRE 16 -1 (2825 700)(3900 700);
FORCEPROP 0 LAST CDS_PHYS_NET_NAME FM_TPM_PRSNT_N
J 0
(3140 740);
PAINT MONO (3140 740);
DISPLAY INVISIBLE (3140 740);
FORCEPROP 2 LAST SIG_NAME FM_TPM_PRSNT_N
J 0
(3165 710);
DISPLAY 0.638298 (3165 710);
PAINT WHITE (3165 710);
WIRE 16 -1 (2825 825)(3900 825);
FORCEPROP 2 LAST SIG_NAME OCP_SFF_CLK_OE_N
J 0
(3190 835);
DISPLAY 0.680851 (3190 835);
PAINT WHITE (3190 835);
WIRE 16 -1 (2825 575)(3900 575);
FORCEPROP 0 LAST CDS_PHYS_NET_NAME VIRTUAL_RESEAT_FPGA_N
J 0
(3140 615);
PAINT MONO (3140 615);
DISPLAY INVISIBLE (3140 615);
FORCEPROP 2 LAST SIG_NAME VIRTUAL_RESEAT_FPGA_N
J 0
(3165 585);
DISPLAY 0.638298 (3165 585);
PAINT WHITE (3165 585);
WIRE 16 -1 (2825 300)(3900 300);
FORCEPROP 0 LAST CDS_PHYS_NET_NAME BMC_MONITER_R
J 0
(3140 340);
PAINT MONO (3140 340);
DISPLAY INVISIBLE (3140 340);
FORCEPROP 2 LAST SIG_NAME BMC_MONITER_R
J 0
(3190 310);
DISPLAY 0.638298 (3190 310);
PAINT WHITE (3190 310);
WIRE 16 -1 (2825 125)(3900 125);
FORCEPROP 0 LAST CDS_PHYS_NET_NAME BIC_MONITER_ISO_R
J 0
(3140 165);
PAINT MONO (3140 165);
DISPLAY INVISIBLE (3140 165);
FORCEPROP 2 LAST SIG_NAME BIC_MONITER_ISO_R
J 0
(3190 135);
DISPLAY 0.638298 (3190 135);
PAINT WHITE (3190 135);
WIRE 16 -1 (2825 450)(3900 450);
FORCEPROP 0 LAST CDS_PHYS_NET_NAME FM_SUSACK_N
J 0
(3140 490);
PAINT MONO (3140 490);
DISPLAY INVISIBLE (3140 490);
FORCEPROP 2 LAST SIG_NAME FM_SUSACK_N
J 0
(3165 460);
DISPLAY 0.638298 (3165 460);
PAINT WHITE (3165 460);
WIRE 16 -1 (2825 -25)(3900 -25);
FORCEPROP 0 LAST CDS_PHYS_NET_NAME FM_SWB_PWR_EN_R
J 0
(3140 15);
PAINT MONO (3140 15);
DISPLAY INVISIBLE (3140 15);
FORCEPROP 2 LAST SIG_NAME FM_SWB_PWR_EN_R
J 0
(3165 -15);
DISPLAY 0.638298 (3165 -15);
PAINT WHITE (3165 -15);
WIRE 16 -1 (1550 -650)(2625 -650);
FORCEPROP 0 LAST CDS_PHYS_NET_NAME IRQ_HSC_FAULT_N
J 0
(1575 -608);
PAINT MONO (1575 -608);
DISPLAY INVISIBLE (1575 -608);
FORCEPROP 0 LAST SIG_NAME IRQ_HSC_FAULT_N
J 0
(1665 -640);
DISPLAY 0.680851 (1665 -640);
PAINT WHITE (1665 -640);
WIRE 16 -1 (1850 3575)(2900 3575);
FORCEPROP 0 LAST CDS_PHYS_NET_NAME PWRGD_PVCCFA_EHV_FIVRA_CPU0
J 0
(1875 3617);
PAINT MONO (1875 3617);
DISPLAY INVISIBLE (1875 3617);
FORCEPROP 0 LAST SIG_NAME PWRGD_PVCCFA_EHV_FIVRA_CPU0
J 0
(2015 3585);
DISPLAY 0.680851 (2015 3585);
PAINT WHITE (2015 3585);
WIRE 16 -1 (1850 3625)(2900 3625);
FORCEPROP 0 LAST CDS_PHYS_NET_NAME PWRGD_PVCCD_HV_CPU0
J 0
(1875 3667);
PAINT MONO (1875 3667);
DISPLAY INVISIBLE (1875 3667);
FORCEPROP 0 LAST SIG_NAME PWRGD_PVCCD_HV_CPU0
J 0
(2015 3635);
DISPLAY 0.680851 (2015 3635);
PAINT WHITE (2015 3635);
WIRE 16 -1 (1850 3675)(2900 3675);
FORCEPROP 0 LAST CDS_PHYS_NET_NAME PWRGD_P3V3_AUX_PLD
J 0
(1875 3717);
PAINT MONO (1875 3717);
DISPLAY INVISIBLE (1875 3717);
FORCEPROP 0 LAST SIG_NAME PWRGD_P3V3_AUX_PLD
J 0
(2015 3685);
DISPLAY 0.680851 (2015 3685);
PAINT WHITE (2015 3685);
WIRE 16 -1 (1850 3525)(2900 3525);
FORCEPROP 0 LAST CDS_PHYS_NET_NAME PWRGD_PVCCIN_CPU0
J 0
(1875 3567);
PAINT MONO (1875 3567);
DISPLAY INVISIBLE (1875 3567);
FORCEPROP 0 LAST SIG_NAME PWRGD_PVCCIN_CPU0
J 0
(2015 3535);
DISPLAY 0.680851 (2015 3535);
PAINT WHITE (2015 3535);
WIRE 16 -1 (1850 3475)(2900 3475);
FORCEPROP 0 LAST CDS_PHYS_NET_NAME PWRGD_PVNN_MAIN_CPU0
J 0
(1875 3517);
PAINT MONO (1875 3517);
DISPLAY INVISIBLE (1875 3517);
FORCEPROP 0 LAST SIG_NAME PWRGD_PVNN_MAIN_CPU0
J 0
(2015 3485);
DISPLAY 0.680851 (2015 3485);
PAINT WHITE (2015 3485);
WIRE 16 -1 (1850 3425)(2900 3425);
FORCEPROP 0 LAST CDS_PHYS_NET_NAME PWRGD_PVNN_PCH_AUX
J 0
(1875 3467);
PAINT MONO (1875 3467);
DISPLAY INVISIBLE (1875 3467);
FORCEPROP 0 LAST SIG_NAME PWRGD_PVNN_PCH_AUX
J 0
(2015 3435);
DISPLAY 0.680851 (2015 3435);
PAINT WHITE (2015 3435);
WIRE 16 -1 (1850 3375)(2900 3375);
FORCEPROP 0 LAST CDS_PHYS_NET_NAME PWRGD_PVNN_MAIN_CPU1
J 0
(1875 3417);
PAINT MONO (1875 3417);
DISPLAY INVISIBLE (1875 3417);
FORCEPROP 0 LAST SIG_NAME PWRGD_PVNN_MAIN_CPU1
J 0
(2015 3385);
DISPLAY 0.680851 (2015 3385);
PAINT WHITE (2015 3385);
WIRE 16 -1 (1850 3325)(2900 3325);
FORCEPROP 0 LAST CDS_PHYS_NET_NAME PWRGD_PVPP_HBM_CPU0
J 0
(1875 3367);
PAINT MONO (1875 3367);
DISPLAY INVISIBLE (1875 3367);
FORCEPROP 0 LAST SIG_NAME PWRGD_PVPP_HBM_CPU0
J 0
(2015 3335);
DISPLAY 0.680851 (2015 3335);
PAINT WHITE (2015 3335);
WIRE 16 -1 (-1450 2025)(-250 2025);
FORCEPROP 0 LAST CDS_PHYS_NET_NAME GPU_BASE_HMC_READY_ISO_R
J 0
(-1425 2067);
PAINT MONO (-1425 2067);
DISPLAY INVISIBLE (-1425 2067);
FORCEPROP 0 LAST SIG_NAME GPU_BASE_HMC_READY_ISO_R
J 0
(-1350 2035);
DISPLAY 0.680851 (-1350 2035);
PAINT WHITE (-1350 2035);
WIRE 16 -1 (-1450 1975)(-250 1975);
FORCEPROP 0 LAST CDS_PHYS_NET_NAME GPU_HMC_PRSNT_ISO_R_N
J 0
(-1425 2017);
PAINT MONO (-1425 2017);
DISPLAY INVISIBLE (-1425 2017);
FORCEPROP 0 LAST SIG_NAME GPU_HMC_PRSNT_ISO_R_N
J 0
(-1350 1985);
DISPLAY 0.680851 (-1350 1985);
PAINT WHITE (-1350 1985);
WIRE 16 -1 (-3375 -1125)(-2325 -1125);
FORCEPROP 2 LAST SIG_NAME GPU_FPGA_OVERT_ISO_N
J 0
(-3260 -1115);
DISPLAY 0.553191 (-3260 -1115);
PAINT WHITE (-3260 -1115);
WIRE 16 -1 (-3375 -1000)(-2325 -1000);
FORCEPROP 2 LAST SIG_NAME GPU_FPGA_EROT_RECOV_N
J 0
(-3260 -990);
DISPLAY 0.553191 (-3260 -990);
PAINT WHITE (-3260 -990);
WIRE 16 -1 (-2125 -625)(-850 -625);
FORCEPROP 0 LAST CDS_PHYS_NET_NAME GPU_BASE_HMC_READY_ISO_R
J 0
(-2100 -583);
PAINT MONO (-2100 -583);
DISPLAY INVISIBLE (-2100 -583);
FORCEPROP 0 LAST SIG_NAME GPU_BASE_HMC_READY_ISO_R
J 0
(-1760 -615);
DISPLAY 0.680851 (-1760 -615);
PAINT WHITE (-1760 -615);
WIRE 16 -1 (-3375 -1675)(-2375 -1675);
FORCEPROP 0 LAST CDS_PHYS_NET_NAME RST_SRST_PLD_BMC_R_N
J 0
(-3350 -1633);
PAINT MONO (-3350 -1633);
DISPLAY INVISIBLE (-3350 -1633);
FORCEPROP 0 LAST SIG_NAME RST_SRST_PLD_BMC_R_N
J 0
(-3275 -1665);
DISPLAY 0.680851 (-3275 -1665);
PAINT WHITE (-3275 -1665);
WIRE 16 -1 (-3375 -1500)(-2325 -1500);
FORCEPROP 2 LAST SIG_NAME GPU_FPGA_EROT_FATALERR_ISO_N
J 0
(-3260 -1490);
DISPLAY 0.553191 (-3260 -1490);
PAINT WHITE (-3260 -1490);
WIRE 16 -1 (-3375 -1375)(-2325 -1375);
FORCEPROP 2 LAST SIG_NAME GPU_PRSNT_N_ISO
J 0
(-3260 -1365);
DISPLAY 0.553191 (-3260 -1365);
PAINT WHITE (-3260 -1365);
WIRE 16 -1 (-3375 -1250)(-2325 -1250);
FORCEPROP 2 LAST SIG_NAME GPU_WP_HW_CTRL_N
J 0
(-3260 -1240);
DISPLAY 0.553191 (-3260 -1240);
PAINT WHITE (-3260 -1240);
WIRE 16 -1 (-2125 -750)(-850 -750);
FORCEPROP 0 LAST CDS_PHYS_NET_NAME GPU_HMC_PRSNT_ISO_R_N
J 0
(-2100 -708);
PAINT MONO (-2100 -708);
DISPLAY INVISIBLE (-2100 -708);
FORCEPROP 0 LAST SIG_NAME GPU_HMC_PRSNT_ISO_R_N
J 0
(-1760 -740);
DISPLAY 0.680851 (-1760 -740);
PAINT WHITE (-1760 -740);
WIRE 16 -1 (-2125 -875)(-850 -875);
FORCEPROP 0 LAST CDS_PHYS_NET_NAME GPU_FPGA_BOOT_EN_R
J 0
(-2100 -833);
PAINT MONO (-2100 -833);
DISPLAY INVISIBLE (-2100 -833);
FORCEPROP 0 LAST SIG_NAME GPU_FPGA_BOOT_EN_R
J 0
(-1760 -865);
DISPLAY 0.680851 (-1760 -865);
PAINT WHITE (-1760 -865);
WIRE 16 -1 (-2125 -1000)(-850 -1000);
FORCEPROP 0 LAST CDS_PHYS_NET_NAME GPU_FPGA_EROT_RECOV_R_N
J 0
(-2100 -958);
PAINT MONO (-2100 -958);
DISPLAY INVISIBLE (-2100 -958);
FORCEPROP 0 LAST SIG_NAME GPU_FPGA_EROT_RECOV_R_N
J 0
(-1760 -990);
DISPLAY 0.680851 (-1760 -990);
PAINT WHITE (-1760 -990);
WIRE 16 -1 (-2125 -1250)(-850 -1250);
FORCEPROP 0 LAST CDS_PHYS_NET_NAME GPU_WP_HW_CTRL_R_N
J 0
(-2100 -1208);
PAINT MONO (-2100 -1208);
DISPLAY INVISIBLE (-2100 -1208);
FORCEPROP 0 LAST SIG_NAME GPU_WP_HW_CTRL_R_N
J 0
(-1760 -1240);
DISPLAY 0.680851 (-1760 -1240);
PAINT WHITE (-1760 -1240);
WIRE 16 -1 (-2175 -1675)(-825 -1675);
FORCEPROP 0 LAST CDS_PHYS_NET_NAME RST_SRST_PLD_BMC_N
J 0
(-1860 -1635);
PAINT MONO (-1860 -1635);
DISPLAY INVISIBLE (-1860 -1635);
FORCEPROP 2 LAST SIG_NAME RST_SRST_PLD_BMC_N
J 0
(-1810 -1665);
DISPLAY 0.638298 (-1810 -1665);
PAINT WHITE (-1810 -1665);
WIRE 16 2175 (-3700 -1575)(-450 -1575);
WIRE 16 2175 (-450 -1575)(-450 -1775);
WIRE 16 2175 (-3700 -1575)(-3700 -1775);
WIRE 16 2175 (-3700 -1775)(-450 -1775);
WIRE 16 -1 (-2125 -1500)(-850 -1500);
FORCEPROP 0 LAST CDS_PHYS_NET_NAME GPU_FPGA_EROT_FATALERR_ISO_R_N
J 0
(-2100 -1458);
PAINT MONO (-2100 -1458);
DISPLAY INVISIBLE (-2100 -1458);
FORCEPROP 0 LAST SIG_NAME GPU_FPGA_EROT_FATALERR_ISO_R_N
J 0
(-1760 -1490);
DISPLAY 0.680851 (-1760 -1490);
PAINT WHITE (-1760 -1490);
WIRE 16 -1 (-2125 -1125)(-850 -1125);
FORCEPROP 0 LAST CDS_PHYS_NET_NAME GPU_FPGA_OVERT_ISO_R_N
J 0
(-2100 -1083);
PAINT MONO (-2100 -1083);
DISPLAY INVISIBLE (-2100 -1083);
FORCEPROP 0 LAST SIG_NAME GPU_FPGA_OVERT_ISO_R_N
J 0
(-1760 -1115);
DISPLAY 0.680851 (-1760 -1115);
PAINT WHITE (-1760 -1115);
WIRE 16 -1 (-1450 2175)(-250 2175);
FORCEPROP 0 LAST CDS_PHYS_NET_NAME GPU_NVS_PWR_BRAKE_R_N
J 0
(-1425 2217);
PAINT MONO (-1425 2217);
DISPLAY INVISIBLE (-1425 2217);
FORCEPROP 0 LAST SIG_NAME GPU_NVS_PWR_BRAKE_R_N
J 0
(-1350 2185);
DISPLAY 0.680851 (-1350 2185);
PAINT WHITE (-1350 2185);
WIRE 16 -1 (-1450 2225)(-250 2225);
FORCEPROP 0 LAST CDS_PHYS_NET_NAME GPU_FPGA_THERM_OVERT_ISO_R_N
J 0
(-1425 2267);
PAINT MONO (-1425 2267);
DISPLAY INVISIBLE (-1425 2267);
FORCEPROP 0 LAST SIG_NAME GPU_FPGA_THERM_OVERT_ISO_R_N
J 0
(-1350 2235);
DISPLAY 0.680851 (-1350 2235);
PAINT WHITE (-1350 2235);
WIRE 16 -1 (-1450 2725)(-250 2725);
FORCEPROP 0 LAST CDS_PHYS_NET_NAME FM_S3M_CPU0_CPLD_CRC_ERROR
J 0
(-1425 2767);
PAINT MONO (-1425 2767);
DISPLAY INVISIBLE (-1425 2767);
FORCEPROP 0 LAST SIG_NAME FM_S3M_CPU0_CPLD_CRC_ERROR
J 0
(-1335 2735);
DISPLAY 0.680851 (-1335 2735);
PAINT WHITE (-1335 2735);
WIRE 16 -1 (-1450 2775)(-250 2775);
FORCEPROP 0 LAST CDS_PHYS_NET_NAME FM_OCP_SFF_PWR_GOOD_R
J 0
(-1425 2817);
PAINT MONO (-1425 2817);
DISPLAY INVISIBLE (-1425 2817);
FORCEPROP 0 LAST SIG_NAME FM_OCP_SFF_PWR_GOOD_R
J 0
(-1335 2785);
DISPLAY 0.680851 (-1335 2785);
PAINT WHITE (-1335 2785);
WIRE 16 -1 (-1450 2425)(-250 2425);
FORCEPROP 0 LAST CDS_PHYS_NET_NAME FM_SLP_SUS_RSM_RST_N
J 0
(-1425 2467);
PAINT MONO (-1425 2467);
DISPLAY INVISIBLE (-1425 2467);
FORCEPROP 0 LAST SIG_NAME FM_SLP_SUS_RSM_RST_N
J 0
(-1335 2435);
DISPLAY 0.680851 (-1335 2435);
PAINT WHITE (-1335 2435);
WIRE 16 -1 (-250 2375)(-2300 2375);
FORCEPROP 0 LAST CDS_PHYS_NET_NAME PU_RST_DEDI_BUSY_PLD_N
J 0
(-1150 2417);
PAINT MONO (-1150 2417);
DISPLAY INVISIBLE (-1150 2417);
FORCEPROP 0 LAST SIG_NAME PU_RST_DEDI_BUSY_PLD_N
J 0
(-1335 2385);
DISPLAY 0.680851 (-1335 2385);
PAINT WHITE (-1335 2385);
WIRE 16 -1 (-2300 2525)(-2300 2375);
WIRE 16 -1 (-1450 2125)(-250 2125);
FORCEPROP 0 LAST CDS_PHYS_NET_NAME GPU_FPGA_EROT_RST_R_N
J 0
(-1425 2167);
PAINT MONO (-1425 2167);
DISPLAY INVISIBLE (-1425 2167);
FORCEPROP 0 LAST SIG_NAME GPU_FPGA_EROT_RST_R_N
J 0
(-1350 2135);
DISPLAY 0.680851 (-1350 2135);
PAINT WHITE (-1350 2135);
WIRE 16 -1 (-1450 2075)(-250 2075);
FORCEPROP 0 LAST CDS_PHYS_NET_NAME GPU_BASE_STBY_EN_R
J 0
(-1425 2117);
PAINT MONO (-1425 2117);
DISPLAY INVISIBLE (-1425 2117);
FORCEPROP 0 LAST SIG_NAME GPU_BASE_STBY_EN_R
J 0
(-1350 2085);
DISPLAY 0.680851 (-1350 2085);
PAINT WHITE (-1350 2085);
WIRE 16 -1 (-1450 2475)(-250 2475);
FORCEPROP 0 LAST CDS_PHYS_NET_NAME IRQ_SML1_PMBUS_PLD_ALERT_N
J 0
(-1425 2517);
PAINT MONO (-1425 2517);
DISPLAY INVISIBLE (-1425 2517);
FORCEPROP 0 LAST SIG_NAME IRQ_SML1_PMBUS_PLD_ALERT_N
J 0
(-1335 2485);
DISPLAY 0.680851 (-1335 2485);
PAINT WHITE (-1335 2485);
WIRE 16 -1 (-1450 2525)(-250 2525);
FORCEPROP 0 LAST CDS_PHYS_NET_NAME IRQ_SML0_ALERT_R_N
J 0
(-1425 2567);
PAINT MONO (-1425 2567);
DISPLAY INVISIBLE (-1425 2567);
FORCEPROP 0 LAST SIG_NAME IRQ_SML0_ALERT_R_N
J 0
(-1335 2535);
DISPLAY 0.680851 (-1335 2535);
PAINT WHITE (-1335 2535);
WIRE 16 -1 (-1450 2575)(-250 2575);
FORCEPROP 0 LAST CDS_PHYS_NET_NAME IRQ_SML1_PMBUS_BMC_ALERT_N
J 0
(-1425 2617);
PAINT MONO (-1425 2617);
DISPLAY INVISIBLE (-1425 2617);
FORCEPROP 0 LAST SIG_NAME IRQ_SML1_PMBUS_BMC_ALERT_N
J 0
(-1335 2585);
DISPLAY 0.680851 (-1335 2585);
PAINT WHITE (-1335 2585);
WIRE 16 -1 (-1450 2625)(-250 2625);
FORCEPROP 2 LAST SIG_NAME OCP_SFF_CLK_OE_R_N
J 0
(-1335 2635);
DISPLAY 0.680851 (-1335 2635);
PAINT WHITE (-1335 2635);
WIRE 16 -1 (-1450 2675)(-250 2675);
FORCEPROP 0 LAST CDS_PHYS_NET_NAME FM_S3M_CPU1_CPLD_CRC_ERROR
J 0
(-1425 2717);
PAINT MONO (-1425 2717);
DISPLAY INVISIBLE (-1425 2717);
FORCEPROP 0 LAST SIG_NAME FM_S3M_CPU1_CPLD_CRC_ERROR
J 0
(-1335 2685);
DISPLAY 0.680851 (-1335 2685);
PAINT WHITE (-1335 2685);
WIRE 16 -1 (-1450 2825)(-250 2825);
FORCEPROP 0 LAST CDS_PHYS_NET_NAME FM_OCP_V3_2_PWR_GOOD_R
J 0
(-1425 2867);
PAINT MONO (-1425 2867);
DISPLAY INVISIBLE (-1425 2867);
FORCEPROP 0 LAST SIG_NAME FM_OCP_V3_2_PWR_GOOD_R
J 0
(-1335 2835);
DISPLAY 0.680851 (-1335 2835);
PAINT WHITE (-1335 2835);
WIRE 16 -1 (-1450 2875)(-250 2875);
FORCEPROP 0 LAST CDS_PHYS_NET_NAME OCP_SFF_AUX_PWR_EN
J 0
(-1425 2917);
PAINT MONO (-1425 2917);
DISPLAY INVISIBLE (-1425 2917);
FORCEPROP 0 LAST SIG_NAME OCP_SFF_AUX_PWR_PLD_EN
J 0
(-1335 2885);
DISPLAY 0.680851 (-1335 2885);
PAINT WHITE (-1335 2885);
WIRE 16 -1 (-1450 3025)(-250 3025);
FORCEPROP 0 LAST CDS_PHYS_NET_NAME IRQ_HSC_FAULT_R1_N
J 0
(-1425 3067);
PAINT MONO (-1425 3067);
DISPLAY INVISIBLE (-1425 3067);
FORCEPROP 0 LAST SIG_NAME IRQ_HSC_FAULT_R1_N
J 0
(-1350 3035);
DISPLAY 0.680851 (-1350 3035);
PAINT WHITE (-1350 3035);
WIRE 16 -1 (-1450 2975)(-250 2975);
FORCEPROP 0 LAST CDS_PHYS_NET_NAME FM_PECI_MUX_SEL_N
J 0
(-1425 3017);
PAINT MONO (-1425 3017);
DISPLAY INVISIBLE (-1425 3017);
FORCEPROP 0 LAST SIG_NAME FM_PECI_MUX_SEL_N
J 0
(-1350 2985);
DISPLAY 0.680851 (-1350 2985);
PAINT WHITE (-1350 2985);
WIRE 16 -1 (-1450 2925)(-250 2925);
FORCEPROP 0 LAST CDS_PHYS_NET_NAME OCP_V3_2_AUX_PWR_EN
J 0
(-1425 2967);
PAINT MONO (-1425 2967);
DISPLAY INVISIBLE (-1425 2967);
FORCEPROP 0 LAST SIG_NAME OCP_V3_2_AUX_PWR_PLD_EN
J 0
(-1335 2935);
DISPLAY 0.680851 (-1335 2935);
DOT 1 (-1250 800);
DOT 1 (-3375 475);
DOT 1 (-2400 800);
DOT 1 (2825 4350);
DOT 1 (2825 3725);
DOT 1 (2750 3775);
FORCENOTE
20220504 ADD R4697
(-2175 -1850) 0;
DISPLAY LEFT (-2175 -1850);
DISPLAY 1.063830 (-2175 -1850);
PAINT WHITE (-2175 -1850);
FORCENOTE
20220304 ADD R4625
(2150 1125) 0;
DISPLAY LEFT (2150 1125);
DISPLAY 1.063830 (2150 1125);
PAINT WHITE (2150 1125);
FORCENOTE
20210902 MODIFY FOR GT
(-4125 4425) 0;
DISPLAY LEFT (-4125 4425);
DISPLAY 2.510638 (-4125 4425);
PAINT PINK (-4125 4425);
FORCENOTE
20220727 ADD R4714,R4715
(-400 100) 0;
DISPLAY LEFT (-400 100);
DISPLAY 1.063830 (-400 100);
PAINT WHITE (-400 100);
FORCENOTE
20220823 CHANGE R4714,R4715 TO 33 OHM.
(-400 0) 0;
DISPLAY LEFT (-400 0);
DISPLAY 0.680851 (-400 0);
PAINT WHITE (-400 0);
QUIT
